FILE_TYPE = MACRO_DRAWING;
SET COLOR_WIRE YELLOW;
SET COLOR_PROP ORANGE;
SET COLOR_DOT WHITE;
SET COLOR_ARC YELLOW;
SET COLOR_BODY GREEN;
SET COLOR_NOTE PURPLE;
SET PROP_DISPLAY VALUE;
SET PAGE_NUMBER P339;
FORCEADD Q_RES..2
(-4025 12275);
FORCEPROP 1 LAST LOCATION PR3844
J 0
(-4000 12350);
DISPLAY 0.723404 (-4000 12350);
PAINT AQUA (-4000 12350);
FORCEPROP 0 LAST $SEC 1
J 0
(-4000 12400);
DISPLAY INVISIBLE (-4000 12400);
FORCEPROP 0 LAST CDS_SEC 1
J 0
(-4000 12400);
DISPLAY INVISIBLE (-4000 12400);
FORCEPROP 1 LASTPIN (-4025 12375) $PN 1
J 0
(-4020 12337);
DISPLAY 0.787234 (-4020 12337);
PAINT MONO (-4020 12337);
DISPLAY INVISIBLE (-4020 12337);
FORCEPROP 1 LASTPIN (-4025 12175) $PN 2
J 0
(-4020 12185);
DISPLAY 0.787234 (-4020 12185);
PAINT MONO (-4020 12185);
DISPLAY INVISIBLE (-4020 12185);
FORCEPROP 0 LAST ROOM NIC_P3V3_BOM2
J 0
(-4000 12050);
DISPLAY 0.553191 (-4000 12050);
PAINT RED (-4000 12050);
FORCEPROP 1 LAST MATERIAL CHIP
J 0
(-4000 12100);
DISPLAY 0.723404 (-4000 12100);
PAINT RED (-4000 12100);
FORCEPROP 1 LAST PACK_TYPE 0402LF
J 0
(-4000 12200);
DISPLAY 0.574468 (-4000 12200);
PAINT SKYBLUE (-4000 12200);
FORCEPROP 1 LAST TOLERANCE 1%
J 0
(-4000 12250);
DISPLAY 0.574468 (-4000 12250);
PAINT SKYBLUE (-4000 12250);
FORCEPROP 1 LAST VALUE 71.5K
J 0
(-4000 12300);
DISPLAY 0.574468 (-4000 12300);
PAINT SKYBLUE (-4000 12300);
FORCEPROP 2 LAST CDS_LIB pure_quanta
J 0
(-4025 12275);
DISPLAY INVISIBLE (-4025 12275);
FORCEPROP 1 LAST WATTAGE 1/16W
J 0
(-4000 12250);
DISPLAY 0.723404 (-4000 12250);
PAINT SKYBLUE (-4000 12250);
DISPLAY INVISIBLE (-4000 12250);
FORCEPROP 1 LAST PATH I100
J 0
(-3975 12450);
DISPLAY 0.978723 (-3975 12450);
PAINT WHITE (-3975 12450);
DISPLAY INVISIBLE (-3975 12450);
FORCEPROP 1 LAST PART_NUMBER CS37152FB05
J 0
(-4000 12150);
DISPLAY 0.468085 (-4000 12150);
PAINT WHITE (-4000 12150);
DISPLAY INVISIBLE (-4000 12150);
FORCEADD UNIVERSAL_GND..1
(-3600 11900);
FORCEPROP 3 LASTPIN (-3600 11950) SIG_NAME GND\g
J 0
(-3590 11960);
DISPLAY 0.659574 (-3590 11960);
PAINT MONO (-3590 11960);
DISPLAY INVISIBLE (-3590 11960);
FORCEPROP 2 LAST CDS_LIB pure_quanta_power
J 0
(-3600 11900);
DISPLAY INVISIBLE (-3600 11900);
FORCEPROP 1 LAST HDL_POWER GND
J 1
(-3575 11825);
DISPLAY 0.872340 (-3575 11825);
PAINT GREEN (-3575 11825);
DISPLAY INVISIBLE (-3575 11825);
FORCEPROP 1 LAST PATH I101
J 0
(-3525 11900);
DISPLAY 0.872340 (-3525 11900);
PAINT AQUA (-3525 11900);
DISPLAY INVISIBLE (-3525 11900);
FORCEADD Q_RES..1
R 1
(-3600 12225);
FORCEPROP 1 LAST LOCATION PR3846
J 0
(-3525 12250);
DISPLAY 0.808511 (-3525 12250);
FORCEPROP 0 LAST $SEC 1
R 1
J 0
(-3575 12300);
DISPLAY INVISIBLE (-3575 12300);
FORCEPROP 0 LAST CDS_SEC 1
R 1
J 0
(-3575 12300);
DISPLAY INVISIBLE (-3575 12300);
FORCEPROP 1 LASTPIN (-3600 12125) $PN 1
R 1
J 0
(-3612 12137);
DISPLAY 0.787234 (-3612 12137);
PAINT MONO (-3612 12137);
DISPLAY INVISIBLE (-3612 12137);
FORCEPROP 1 LASTPIN (-3600 12325) $PN 2
R 1
J 0
(-3612 12287);
DISPLAY 0.787234 (-3612 12287);
PAINT MONO (-3612 12287);
DISPLAY INVISIBLE (-3612 12287);
FORCEPROP 1 LAST VALUE 1.33K
J 0
(-3525 12200);
DISPLAY 0.638298 (-3525 12200);
FORCEPROP 1 LAST MATERIAL CHIP
J 0
(-3525 11975);
DISPLAY 0.787234 (-3525 11975);
PAINT RED (-3525 11975);
FORCEPROP 0 LAST ROOM NIC_P3V3_BOM2
J 0
(-3525 11925);
DISPLAY 0.553191 (-3525 11925);
PAINT RED (-3525 11925);
FORCEPROP 1 LAST TOLERANCE 1%
J 0
(-3525 12150);
DISPLAY 0.638298 (-3525 12150);
FORCEPROP 1 LAST PACK_TYPE 0402LF
J 0
(-3525 12100);
DISPLAY 0.638298 (-3525 12100);
FORCEPROP 1 LAST WATTAGE 1/16W
R 1
J 2
(-3450 12200);
DISPLAY 0.978723 (-3450 12200);
DISPLAY INVISIBLE (-3450 12200);
FORCEPROP 2 LAST CDS_LIB pure_quanta
R 1
J 0
(-3600 12225);
DISPLAY INVISIBLE (-3600 12225);
FORCEPROP 1 LAST PATH I102
R 1
J 0
(-3750 12175);
DISPLAY 0.978723 (-3750 12175);
PAINT WHITE (-3750 12175);
DISPLAY INVISIBLE (-3750 12175);
FORCEPROP 1 LAST PART_NUMBER CS21332FB05
J 0
(-3525 12050);
DISPLAY 0.638298 (-3525 12050);
DISPLAY INVISIBLE (-3525 12050);
FORCEADD UNIVERSAL_GND..1
(-3050 11900);
FORCEPROP 3 LASTPIN (-3050 11950) SIG_NAME GND\g
J 0
(-3040 11960);
DISPLAY 0.659574 (-3040 11960);
PAINT MONO (-3040 11960);
DISPLAY INVISIBLE (-3040 11960);
FORCEPROP 2 LAST CDS_LIB pure_quanta_power
J 0
(-3050 11900);
DISPLAY INVISIBLE (-3050 11900);
FORCEPROP 1 LAST HDL_POWER GND
J 1
(-3025 11825);
DISPLAY 0.872340 (-3025 11825);
PAINT GREEN (-3025 11825);
DISPLAY INVISIBLE (-3025 11825);
FORCEPROP 1 LAST PATH I103
J 0
(-2975 11900);
DISPLAY 0.872340 (-2975 11900);
PAINT AQUA (-2975 11900);
DISPLAY INVISIBLE (-2975 11900);
FORCEADD Q_CAP..1
(-3050 12200);
FORCEPROP 1 LAST LOCATION PC2161
J 0
(-3000 12300);
DISPLAY 0.723404 (-3000 12300);
PAINT AQUA (-3000 12300);
FORCEPROP 0 LAST $SEC 1
J 0
(-3000 12350);
DISPLAY INVISIBLE (-3000 12350);
FORCEPROP 0 LAST CDS_SEC 1
J 0
(-3000 12350);
DISPLAY INVISIBLE (-3000 12350);
FORCEPROP 1 LASTPIN (-3050 12300) $PN 1
J 0
(-3040 12280);
DISPLAY 0.787234 (-3040 12280);
PAINT MONO (-3040 12280);
DISPLAY INVISIBLE (-3040 12280);
FORCEPROP 1 LASTPIN (-3050 12100) $PN 2
J 0
(-3040 12080);
DISPLAY 0.787234 (-3040 12080);
PAINT MONO (-3040 12080);
DISPLAY INVISIBLE (-3040 12080);
FORCEPROP 0 LAST ROOM NIC_P3V3_BOM2
J 0
(-3000 12025);
DISPLAY 0.680851 (-3000 12025);
PAINT RED (-3000 12025);
FORCEPROP 1 LAST VALUE 0.068UF
J 0
(-3000 12275);
DISPLAY 0.574468 (-3000 12275);
PAINT SKYBLUE (-3000 12275);
FORCEPROP 1 LAST MATERIAL X7R
J 0
(-3000 12225);
DISPLAY 0.574468 (-3000 12225);
PAINT RED (-3000 12225);
FORCEPROP 1 LAST PACK_TYPE 0402
J 0
(-3000 12125);
DISPLAY 0.574468 (-3000 12125);
PAINT SKYBLUE (-3000 12125);
FORCEPROP 1 LAST VOLTAGE 16V
J 0
(-3000 12175);
DISPLAY 0.574468 (-3000 12175);
PAINT SKYBLUE (-3000 12175);
FORCEPROP 2 LAST CDS_LIB pure_quanta
J 0
(-3050 12200);
DISPLAY INVISIBLE (-3050 12200);
FORCEPROP 1 LAST TOLERANCE 10%
J 0
(-3000 12150);
DISPLAY 0.723404 (-3000 12150);
PAINT SKYBLUE (-3000 12150);
DISPLAY INVISIBLE (-3000 12150);
FORCEPROP 1 LAST PATH I104
J 0
(-3000 12350);
DISPLAY 0.978723 (-3000 12350);
PAINT WHITE (-3000 12350);
DISPLAY INVISIBLE (-3000 12350);
FORCEPROP 1 LAST PART_NUMBER CH3683K1B09
J 0
(-3000 12075);
DISPLAY 0.574468 (-3000 12075);
PAINT WHITE (-3000 12075);
DISPLAY INVISIBLE (-3000 12075);
FORCEADD UNIVERSAL_GND..1
(-1550 11775);
FORCEPROP 3 LASTPIN (-1550 11825) SIG_NAME GND\g
J 0
(-1540 11835);
DISPLAY 0.659574 (-1540 11835);
PAINT MONO (-1540 11835);
DISPLAY INVISIBLE (-1540 11835);
FORCEPROP 2 LAST CDS_LIB pure_quanta_power
J 0
(-1550 11775);
DISPLAY INVISIBLE (-1550 11775);
FORCEPROP 1 LAST HDL_POWER GND
J 1
(-1525 11700);
DISPLAY 0.872340 (-1525 11700);
PAINT GREEN (-1525 11700);
DISPLAY INVISIBLE (-1525 11700);
FORCEPROP 1 LAST PATH I105
J 0
(-1475 11775);
DISPLAY 0.872340 (-1475 11775);
PAINT AQUA (-1475 11775);
DISPLAY INVISIBLE (-1475 11775);
FORCEADD Q_CAP..1
(-1550 12125);
FORCEPROP 1 LAST LOCATION PC2162
J 0
(-1500 12225);
DISPLAY 0.787234 (-1500 12225);
FORCEPROP 0 LAST $SEC 1
J 0
(-1500 12275);
DISPLAY INVISIBLE (-1500 12275);
FORCEPROP 0 LAST CDS_SEC 1
J 0
(-1500 12275);
DISPLAY INVISIBLE (-1500 12275);
FORCEPROP 1 LASTPIN (-1550 12225) $PN 1
J 0
(-1540 12205);
DISPLAY 0.787234 (-1540 12205);
PAINT MONO (-1540 12205);
DISPLAY INVISIBLE (-1540 12205);
FORCEPROP 1 LASTPIN (-1550 12025) $PN 2
J 0
(-1540 12005);
DISPLAY 0.787234 (-1540 12005);
PAINT MONO (-1540 12005);
DISPLAY INVISIBLE (-1540 12005);
FORCEPROP 0 LAST ROOM NIC_P3V3_BOM2
J 0
(-1500 12325);
DISPLAY 0.680851 (-1500 12325);
PAINT RED (-1500 12325);
FORCEPROP 1 LAST PACK_TYPE 0402
J 0
(-1500 11925);
DISPLAY 0.787234 (-1500 11925);
FORCEPROP 1 LAST MATERIAL X7R
J 0
(-1500 12025);
DISPLAY 0.787234 (-1500 12025);
PAINT RED (-1500 12025);
FORCEPROP 1 LAST TOLERANCE 5%
J 0
(-1500 12075);
DISPLAY 0.787234 (-1500 12075);
FORCEPROP 1 LAST VOLTAGE 50V
J 0
(-1500 12125);
DISPLAY 0.787234 (-1500 12125);
FORCEPROP 1 LAST VALUE 100PF
J 0
(-1500 12175);
DISPLAY 0.787234 (-1500 12175);
FORCEPROP 2 LAST CDS_LIB pure_quanta
J 0
(-1550 12125);
DISPLAY INVISIBLE (-1550 12125);
FORCEPROP 1 LAST PATH I106
J 0
(-1500 12275);
DISPLAY 0.978723 (-1500 12275);
PAINT WHITE (-1500 12275);
DISPLAY INVISIBLE (-1500 12275);
FORCEPROP 1 LAST PART_NUMBER CH11006JB18
J 0
(-1500 11975);
DISPLAY 0.787234 (-1500 11975);
DISPLAY INVISIBLE (-1500 11975);
FORCEADD UNIVERSAL_GND..1
(-950 12000);
FORCEPROP 3 LASTPIN (-950 12050) SIG_NAME GND\g
J 0
(-940 12060);
DISPLAY 0.659574 (-940 12060);
PAINT MONO (-940 12060);
DISPLAY INVISIBLE (-940 12060);
FORCEPROP 2 LAST CDS_LIB pure_quanta_power
J 0
(-950 12000);
DISPLAY INVISIBLE (-950 12000);
FORCEPROP 1 LAST HDL_POWER GND
J 1
(-925 11925);
DISPLAY 0.872340 (-925 11925);
PAINT GREEN (-925 11925);
DISPLAY INVISIBLE (-925 11925);
FORCEPROP 1 LAST PATH I107
J 0
(-875 12000);
DISPLAY 0.872340 (-875 12000);
PAINT AQUA (-875 12000);
DISPLAY INVISIBLE (-875 12000);
FORCEADD Q_CAP..1
(-950 12350);
FORCEPROP 1 LAST LOCATION PC2163
J 0
(-900 12425);
DISPLAY 0.723404 (-900 12425);
PAINT AQUA (-900 12425);
FORCEPROP 0 LAST $SEC 1
J 0
(-900 12475);
DISPLAY INVISIBLE (-900 12475);
FORCEPROP 0 LAST CDS_SEC 1
J 0
(-900 12475);
DISPLAY INVISIBLE (-900 12475);
FORCEPROP 1 LASTPIN (-950 12450) $PN 1
J 0
(-940 12430);
DISPLAY 0.787234 (-940 12430);
PAINT MONO (-940 12430);
DISPLAY INVISIBLE (-940 12430);
FORCEPROP 1 LASTPIN (-950 12250) $PN 2
J 0
(-940 12230);
DISPLAY 0.787234 (-940 12230);
PAINT MONO (-940 12230);
DISPLAY INVISIBLE (-940 12230);
FORCEPROP 1 LAST MATERIAL X6S
J 0
(-900 12325);
DISPLAY 0.574468 (-900 12325);
PAINT RED (-900 12325);
FORCEPROP 1 LAST VALUE 10UF
J 0
(-900 12375);
DISPLAY 0.574468 (-900 12375);
PAINT SKYBLUE (-900 12375);
FORCEPROP 1 LAST VOLTAGE 16V
J 0
(-900 12275);
DISPLAY 0.574468 (-900 12275);
PAINT SKYBLUE (-900 12275);
FORCEPROP 1 LAST PACK_TYPE C0805
J 0
(-900 12225);
DISPLAY 0.574468 (-900 12225);
PAINT SKYBLUE (-900 12225);
FORCEPROP 0 LAST ROOM NIC_P3V3_BOM2
J 0
(-900 12525);
DISPLAY 0.680851 (-900 12525);
PAINT RED (-900 12525);
FORCEPROP 1 LAST TOLERANCE 10%
J 0
(-900 12300);
DISPLAY 0.723404 (-900 12300);
PAINT SKYBLUE (-900 12300);
DISPLAY INVISIBLE (-900 12300);
FORCEPROP 2 LAST CDS_LIB pure_quanta
J 0
(-950 12350);
DISPLAY INVISIBLE (-950 12350);
FORCEPROP 1 LAST PATH I108
J 0
(-900 12500);
DISPLAY 0.978723 (-900 12500);
PAINT WHITE (-900 12500);
DISPLAY INVISIBLE (-900 12500);
FORCEPROP 1 LAST PART_NUMBER CH6103KEA01
J 0
(-900 12175);
DISPLAY 0.574468 (-900 12175);
PAINT WHITE (-900 12175);
DISPLAY INVISIBLE (-900 12175);
FORCEADD UNIVERSAL_GND..1
(-3400 12650);
FORCEPROP 3 LASTPIN (-3400 12700) SIG_NAME GND\g
J 0
(-3390 12710);
DISPLAY 0.659574 (-3390 12710);
PAINT MONO (-3390 12710);
DISPLAY INVISIBLE (-3390 12710);
FORCEPROP 2 LAST CDS_LIB pure_quanta_power
J 0
(-3400 12650);
DISPLAY INVISIBLE (-3400 12650);
FORCEPROP 1 LAST HDL_POWER GND
J 1
(-3375 12575);
DISPLAY 0.872340 (-3375 12575);
PAINT GREEN (-3375 12575);
DISPLAY INVISIBLE (-3375 12575);
FORCEPROP 1 LAST PATH I110
J 0
(-3325 12650);
DISPLAY 0.872340 (-3325 12650);
PAINT AQUA (-3325 12650);
DISPLAY INVISIBLE (-3325 12650);
FORCEADD Q_CAP..1
(-3400 12850);
FORCEPROP 1 LAST LOCATION PC2159
J 0
(-3350 12950);
DISPLAY 0.638298 (-3350 12950);
FORCEPROP 0 LAST $SEC 1
J 0
(-3350 13000);
DISPLAY INVISIBLE (-3350 13000);
FORCEPROP 0 LAST CDS_SEC 1
J 0
(-3350 13000);
DISPLAY INVISIBLE (-3350 13000);
FORCEPROP 1 LASTPIN (-3400 12950) $PN 1
J 0
(-3390 12930);
DISPLAY 0.787234 (-3390 12930);
PAINT MONO (-3390 12930);
DISPLAY INVISIBLE (-3390 12930);
FORCEPROP 1 LASTPIN (-3400 12750) $PN 2
J 0
(-3390 12730);
DISPLAY 0.787234 (-3390 12730);
PAINT MONO (-3390 12730);
DISPLAY INVISIBLE (-3390 12730);
FORCEPROP 0 LAST ROOM NIC_P3V3_BOM2
J 0
(-3350 13000);
DISPLAY 0.553191 (-3350 13000);
PAINT RED (-3350 13000);
FORCEPROP 1 LAST PACK_TYPE C0402
J 0
(-3350 12750);
DISPLAY 0.510638 (-3350 12750);
FORCEPROP 1 LAST VOLTAGE 25V
J 0
(-3350 12800);
DISPLAY 0.510638 (-3350 12800);
FORCEPROP 1 LAST VALUE 1UF
J 0
(-3350 12900);
DISPLAY 0.510638 (-3350 12900);
FORCEPROP 1 LAST MATERIAL X6S
J 0
(-3350 12850);
DISPLAY 0.510638 (-3350 12850);
PAINT RED (-3350 12850);
FORCEPROP 2 LAST CDS_LIB pure_quanta
J 0
(-3400 12850);
DISPLAY INVISIBLE (-3400 12850);
FORCEPROP 1 LAST TOLERANCE 10%
J 0
(-3350 12800);
DISPLAY 0.638298 (-3350 12800);
DISPLAY INVISIBLE (-3350 12800);
FORCEPROP 1 LAST PATH I111
J 0
(-3350 13000);
DISPLAY 0.978723 (-3350 13000);
PAINT WHITE (-3350 13000);
DISPLAY INVISIBLE (-3350 13000);
FORCEPROP 1 LAST PART_NUMBER CH5104KEB02
J 0
(-3350 12700);
DISPLAY 0.510638 (-3350 12700);
DISPLAY INVISIBLE (-3350 12700);
FORCEADD UNIVERSAL_POWER..1
R 2
(-3325 13225);
FORCEPROP 3 LASTPIN (-3325 13175) SIG_NAME P3V3_AUX\g
J 0
(-3315 13185);
DISPLAY 0.659574 (-3315 13185);
PAINT MONO (-3315 13185);
DISPLAY INVISIBLE (-3315 13185);
FORCEPROP 1 LAST HDL_POWER P3V3_AUX
J 1
(-3325 13275);
DISPLAY 0.723404 (-3325 13275);
PAINT GREEN (-3325 13275);
FORCEPROP 2 LAST CDS_LIB pure_quanta_power
J 0
(-3325 13225);
DISPLAY INVISIBLE (-3325 13225);
FORCEPROP 1 LAST PATH I112
J 2
(-3375 13250);
DISPLAY 0.872340 (-3375 13250);
PAINT AQUA (-3375 13250);
DISPLAY INVISIBLE (-3375 13250);
FORCEADD MP5016GQHLZ..1
(-2400 12525);
FORCEPROP 1 LAST LOCATION PU205
J 0
(-2645 13006);
DISPLAY 0.723404 (-2645 13006);
PAINT GREEN (-2645 13006);
FORCEPROP 0 LAST $SEC 1
J 0
(-2625 13150);
DISPLAY INVISIBLE (-2625 13150);
FORCEPROP 0 LAST CDS_SEC 1
J 0
(-2625 13150);
DISPLAY INVISIBLE (-2625 13150);
FORCEPROP 0 LASTPIN (-2800 12375) $PN 10
J 2
(-2810 12385);
DISPLAY 0.808511 (-2810 12385);
FORCEPROP 0 LASTPIN (-2800 12575) $PN 9
J 2
(-2810 12585);
DISPLAY 0.808511 (-2810 12585);
FORCEPROP 0 LASTPIN (-2000 12475) $PN 8
J 0
(-1990 12485);
DISPLAY 0.808511 (-1990 12485);
FORCEPROP 0 LASTPIN (-2000 12375) $PN 3
J 0
(-1990 12385);
DISPLAY 0.808511 (-1990 12385);
FORCEPROP 0 LASTPIN (-2800 12425) $PN 4
J 2
(-2810 12435);
DISPLAY 0.808511 (-2810 12435);
FORCEPROP 0 LASTPIN (-2800 12475) $PN 5
J 2
(-2810 12485);
DISPLAY 0.808511 (-2810 12485);
FORCEPROP 0 LASTPIN (-2000 12675) $PN 6_7
J 0
(-1990 12685);
DISPLAY 0.808511 (-1990 12685);
FORCEPROP 0 LASTPIN (-2800 12675) $PN 1_2
J 2
(-2810 12685);
DISPLAY 0.808511 (-2810 12685);
FORCEPROP 2 LAST PART_TYPE SMLF
J 0
(-2625 13100);
DISPLAY 0.680851 (-2625 13100);
FORCEPROP 2 LAST VALUE MP5016GQH-L-Z
J 0
(-2625 13050);
DISPLAY 0.680851 (-2625 13050);
FORCEPROP 0 LAST ROOM NIC_P3V3_BOM2
J 0
(-2625 13200);
DISPLAY 0.680851 (-2625 13200);
PAINT RED (-2625 13200);
FORCEPROP 1 LAST MATERIAL IC
J 0
(-2645 12732);
DISPLAY 0.723404 (-2645 12732);
PAINT RED (-2645 12732);
FORCEPROP 2 LAST CDS_LIB pure_quanta
J 0
(-2400 12525);
DISPLAY INVISIBLE (-2400 12525);
FORCEPROP 1 LAST CDS_LMAN_SYM_OUTLINE -250,200,250,-200
J 0
(-2400 12525);
DISPLAY 0.468085 (-2400 12525);
PAINT GREEN (-2400 12525);
DISPLAY INVISIBLE (-2400 12525);
FORCEPROP 1 LAST NEEDS_NO_SIZE TRUE
J 0
(-2400 12525);
DISPLAY 0.723404 (-2400 12525);
PAINT GREEN (-2400 12525);
DISPLAY INVISIBLE (-2400 12525);
FORCEPROP 1 LAST PATH I113
J 0
(-2400 12525);
DISPLAY 0.723404 (-2400 12525);
PAINT GREEN (-2400 12525);
DISPLAY INVISIBLE (-2400 12525);
FORCEPROP 1 LAST PART_NUMBER AL005016007
J 0
(-2645 12859);
DISPLAY 0.723404 (-2645 12859);
PAINT GREEN (-2645 12859);
DISPLAY INVISIBLE (-2645 12859);
FORCEADD UNIVERSAL_POWER..1
R 2
(-950 13000);
FORCEPROP 3 LASTPIN (-950 12950) SIG_NAME P3V3_OCP_SFF_R\g
J 0
(-940 12960);
DISPLAY 0.659574 (-940 12960);
PAINT MONO (-940 12960);
DISPLAY INVISIBLE (-940 12960);
FORCEPROP 1 LAST HDL_POWER P3V3_OCP_SFF_R
J 1
(-950 13050);
DISPLAY 0.723404 (-950 13050);
PAINT GREEN (-950 13050);
FORCEPROP 2 LAST CDS_LIB pure_quanta_power
J 0
(-950 13000);
DISPLAY INVISIBLE (-950 13000);
FORCEPROP 1 LAST PATH I114
J 2
(-1000 13025);
DISPLAY 0.872340 (-1000 13025);
PAINT AQUA (-1000 13025);
DISPLAY INVISIBLE (-1000 13025);
FORCEADD Q_RES..1
(-7725 9600);
FORCEPROP 1 LAST LOCATION R3834
J 0
(-7775 9625);
DISPLAY 0.638298 (-7775 9625);
FORCEPROP 0 LAST $SEC 1
J 0
(-7775 9675);
DISPLAY 0.680851 (-7775 9675);
PAINT MONO (-7775 9675);
DISPLAY INVISIBLE (-7775 9675);
FORCEPROP 0 LAST CDS_SEC 1
J 0
(-7775 9675);
DISPLAY 0.680851 (-7775 9675);
DISPLAY INVISIBLE (-7775 9675);
FORCEPROP 1 LASTPIN (-7825 9600) $PN 1
J 0
(-7813 9612);
DISPLAY 0.787234 (-7813 9612);
PAINT MONO (-7813 9612);
FORCEPROP 1 LASTPIN (-7625 9600) $PN 2
J 0
(-7663 9612);
DISPLAY 0.787234 (-7663 9612);
PAINT MONO (-7663 9612);
FORCEPROP 1 LAST MATERIAL EMPTY
J 0
(-7925 9600);
DISPLAY 0.510638 (-7925 9600);
PAINT RED (-7925 9600);
FORCEPROP 1 LAST TOLERANCE 5%
J 0
(-7550 9600);
DISPLAY 0.510638 (-7550 9600);
FORCEPROP 1 LAST VALUE 0
J 2
(-7575 9600);
DISPLAY 0.510638 (-7575 9600);
FORCEPROP 0 LAST ROOM NIC_P12V_MPS_MAM_BOM2
J 0
(-8150 9675);
DISPLAY 0.680851 (-8150 9675);
PAINT RED (-8150 9675);
FORCEPROP 1 LAST PACK_TYPE 0402LF
J 0
(-7475 9600);
DISPLAY 0.510638 (-7475 9600);
DISPLAY INVISIBLE (-7475 9600);
FORCEPROP 1 LAST WATTAGE 1/16W
J 2
(-7625 9525);
DISPLAY 0.319149 (-7625 9525);
DISPLAY INVISIBLE (-7625 9525);
FORCEPROP 2 LAST CDS_LIB pure_quanta
J 0
(-7725 9600);
DISPLAY INVISIBLE (-7725 9600);
FORCEPROP 1 LAST PATH I128
J 0
(-7775 9750);
DISPLAY 0.978723 (-7775 9750);
PAINT WHITE (-7775 9750);
DISPLAY INVISIBLE (-7775 9750);
FORCEPROP 1 LAST PART_NUMBER CS00002JB13
J 0
(-7800 9550);
DISPLAY 0.319149 (-7800 9550);
DISPLAY INVISIBLE (-7800 9550);
FORCEADD OFFPAGE..1
(-8875 9975);
PAINT AQUA (-8875 9975);
FORCEPROP 2 LAST $XR0 136 
J 0
(-9127 9975);
DISPLAY 0.638298 (-9127 9975);
PAINT MONO (-9127 9975);
FORCEPROP 2 LAST $XR1 134 
J 0
(-9247 9975);
DISPLAY 0.638298 (-9247 9975);
PAINT MONO (-9247 9975);
FORCEPROP 2 LAST $XR2 135 
J 0
(-9367 9975);
DISPLAY 0.638298 (-9367 9975);
PAINT MONO (-9367 9975);
FORCEPROP 2 LAST $XR3 248 
J 0
(-9487 9975);
DISPLAY 0.638298 (-9487 9975);
PAINT MONO (-9487 9975);
FORCEPROP 2 LAST CDS_LIB standard
J 0
(-8875 9975);
DISPLAY INVISIBLE (-8875 9975);
FORCEPROP 1 LAST OFFPAGE TRUE
J 0
(-8550 9850);
DISPLAY 0.872340 (-8550 9850);
PAINT AQUA (-8550 9850);
DISPLAY INVISIBLE (-8550 9850);
FORCEPROP 1 LAST COMMENT_BODY TRUE
J 0
(-8750 9875);
DISPLAY 0.872340 (-8750 9875);
PAINT GREEN (-8750 9875);
DISPLAY INVISIBLE (-8750 9875);
FORCEPROP 2 LAST PATH I129
J 0
(-8825 10050);
DISPLAY 0.680851 (-8825 10050);
DISPLAY INVISIBLE (-8825 10050);
FORCEADD Q_RES..1
(-7825 9975);
FORCEPROP 1 LAST LOCATION R591
J 0
(-8025 9975);
DISPLAY 0.638298 (-8025 9975);
FORCEPROP 0 LAST $SEC 1
J 0
(-8025 10025);
DISPLAY 0.680851 (-8025 10025);
PAINT MONO (-8025 10025);
DISPLAY INVISIBLE (-8025 10025);
FORCEPROP 0 LAST CDS_SEC 1
J 0
(-8025 10025);
DISPLAY 0.680851 (-8025 10025);
DISPLAY INVISIBLE (-8025 10025);
FORCEPROP 1 LASTPIN (-7925 9975) $PN 1
J 0
(-7913 9987);
DISPLAY 0.787234 (-7913 9987);
PAINT MONO (-7913 9987);
FORCEPROP 1 LASTPIN (-7725 9975) $PN 2
J 0
(-7763 9987);
DISPLAY 0.787234 (-7763 9987);
PAINT MONO (-7763 9987);
FORCEPROP 1 LAST VALUE 0
J 2
(-7675 9975);
DISPLAY 0.510638 (-7675 9975);
FORCEPROP 1 LAST TOLERANCE 5%
J 0
(-7650 9975);
DISPLAY 0.510638 (-7650 9975);
FORCEPROP 1 LAST MATERIAL CHIP
J 0
(-7600 9975);
DISPLAY 0.510638 (-7600 9975);
FORCEPROP 0 LAST ROOM NIC_P12V_MPS_MAM_BOM2
J 0
(-8125 10050);
DISPLAY 0.680851 (-8125 10050);
PAINT RED (-8125 10050);
FORCEPROP 1 LAST WATTAGE 1/16W
J 2
(-7725 9900);
DISPLAY 0.319149 (-7725 9900);
DISPLAY INVISIBLE (-7725 9900);
FORCEPROP 1 LAST PACK_TYPE 0402LF
J 0
(-7575 9975);
DISPLAY 0.510638 (-7575 9975);
DISPLAY INVISIBLE (-7575 9975);
FORCEPROP 2 LAST CDS_LIB pure_quanta
J 0
(-7825 9975);
DISPLAY INVISIBLE (-7825 9975);
FORCEPROP 1 LAST PATH I130
J 0
(-7875 10125);
DISPLAY 0.978723 (-7875 10125);
PAINT WHITE (-7875 10125);
DISPLAY INVISIBLE (-7875 10125);
FORCEPROP 1 LAST PART_NUMBER CS00002JB13
J 0
(-7900 9925);
DISPLAY 0.319149 (-7900 9925);
DISPLAY INVISIBLE (-7900 9925);
FORCEADD Q_RES..1
(-3850 12575);
FORCEPROP 1 LAST LOCATION R3845
J 0
(-3900 12600);
DISPLAY 0.638298 (-3900 12600);
FORCEPROP 0 LAST $SEC 1
J 0
(-3900 12650);
DISPLAY 0.680851 (-3900 12650);
PAINT MONO (-3900 12650);
DISPLAY INVISIBLE (-3900 12650);
FORCEPROP 0 LAST CDS_SEC 1
J 0
(-3900 12650);
DISPLAY 0.680851 (-3900 12650);
DISPLAY INVISIBLE (-3900 12650);
FORCEPROP 1 LASTPIN (-3950 12575) $PN 1
J 0
(-3938 12587);
DISPLAY 0.787234 (-3938 12587);
PAINT MONO (-3938 12587);
FORCEPROP 1 LASTPIN (-3750 12575) $PN 2
J 0
(-3788 12587);
DISPLAY 0.787234 (-3788 12587);
PAINT MONO (-3788 12587);
FORCEPROP 1 LAST PACK_TYPE 0402LF
J 0
(-4075 12600);
DISPLAY 0.510638 (-4075 12600);
FORCEPROP 1 LAST MATERIAL EMPTY
J 0
(-4075 12575);
DISPLAY 0.510638 (-4075 12575);
PAINT RED (-4075 12575);
FORCEPROP 0 LAST ROOM NIC_P3V3_BOM2
J 0
(-4075 12525);
DISPLAY 0.680851 (-4075 12525);
PAINT RED (-4075 12525);
FORCEPROP 1 LAST TOLERANCE 5%
J 0
(-3675 12575);
DISPLAY 0.510638 (-3675 12575);
FORCEPROP 1 LAST VALUE 0
J 2
(-3700 12575);
DISPLAY 0.510638 (-3700 12575);
FORCEPROP 2 LAST CDS_LIB pure_quanta
J 0
(-3850 12575);
DISPLAY INVISIBLE (-3850 12575);
FORCEPROP 1 LAST WATTAGE 1/16W
J 2
(-3750 12500);
DISPLAY 0.319149 (-3750 12500);
DISPLAY INVISIBLE (-3750 12500);
FORCEPROP 1 LAST PATH I131
J 0
(-3900 12725);
DISPLAY 0.978723 (-3900 12725);
PAINT WHITE (-3900 12725);
DISPLAY INVISIBLE (-3900 12725);
FORCEPROP 1 LAST PART_NUMBER CS00002JB13
J 0
(-3925 12525);
DISPLAY 0.319149 (-3925 12525);
DISPLAY INVISIBLE (-3925 12525);
FORCEADD OFFPAGE..1
(-5325 12900);
PAINT AQUA (-5325 12900);
FORCEPROP 2 LAST $XR0 134 
J 0
(-5607 12900);
DISPLAY 0.638298 (-5607 12900);
PAINT MONO (-5607 12900);
FORCEPROP 2 LAST $XR1 135 
J 0
(-5727 12900);
DISPLAY 0.638298 (-5727 12900);
PAINT MONO (-5727 12900);
FORCEPROP 2 LAST $XR2 136 
J 0
(-5847 12900);
DISPLAY 0.638298 (-5847 12900);
PAINT MONO (-5847 12900);
FORCEPROP 2 LAST $XR3 248 
J 0
(-5967 12900);
DISPLAY 0.638298 (-5967 12900);
PAINT MONO (-5967 12900);
FORCEPROP 2 LAST CDS_LIB standard
J 0
(-5325 12900);
DISPLAY INVISIBLE (-5325 12900);
FORCEPROP 1 LAST OFFPAGE TRUE
J 0
(-5000 12775);
DISPLAY 0.872340 (-5000 12775);
PAINT AQUA (-5000 12775);
DISPLAY INVISIBLE (-5000 12775);
FORCEPROP 1 LAST COMMENT_BODY TRUE
J 0
(-5200 12800);
DISPLAY 0.872340 (-5200 12800);
PAINT GREEN (-5200 12800);
DISPLAY INVISIBLE (-5200 12800);
FORCEPROP 2 LAST PATH I133
J 0
(-5275 12975);
DISPLAY 0.680851 (-5275 12975);
DISPLAY INVISIBLE (-5275 12975);
FORCEADD Q_RES..1
(-4000 13325);
FORCEPROP 1 LAST LOCATION R1487
J 0
(-4200 13325);
DISPLAY 0.638298 (-4200 13325);
FORCEPROP 0 LAST $SEC 1
J 0
(-4200 13475);
DISPLAY 0.680851 (-4200 13475);
PAINT MONO (-4200 13475);
DISPLAY INVISIBLE (-4200 13475);
FORCEPROP 0 LAST CDS_SEC 1
J 0
(-4200 13475);
DISPLAY 0.680851 (-4200 13475);
DISPLAY INVISIBLE (-4200 13475);
FORCEPROP 1 LASTPIN (-4100 13325) $PN 1
J 0
(-4088 13337);
DISPLAY 0.787234 (-4088 13337);
PAINT MONO (-4088 13337);
FORCEPROP 1 LASTPIN (-3900 13325) $PN 2
J 0
(-3938 13337);
DISPLAY 0.787234 (-3938 13337);
PAINT MONO (-3938 13337);
FORCEPROP 1 LAST MATERIAL CHIP
J 0
(-3775 13325);
DISPLAY 0.510638 (-3775 13325);
FORCEPROP 1 LAST VALUE 0
J 2
(-3850 13325);
DISPLAY 0.510638 (-3850 13325);
FORCEPROP 1 LAST TOLERANCE 5%
J 0
(-3825 13325);
DISPLAY 0.510638 (-3825 13325);
FORCEPROP 0 LAST ROOM NIC_P3V3_BOM2
J 0
(-4200 13425);
DISPLAY 0.680851 (-4200 13425);
PAINT RED (-4200 13425);
FORCEPROP 2 LAST CDS_LIB pure_quanta
J 0
(-4000 13325);
DISPLAY INVISIBLE (-4000 13325);
FORCEPROP 1 LAST WATTAGE 1/16W
J 2
(-3900 13250);
DISPLAY 0.319149 (-3900 13250);
DISPLAY INVISIBLE (-3900 13250);
FORCEPROP 1 LAST PACK_TYPE 0402LF
J 0
(-3750 13325);
DISPLAY 0.510638 (-3750 13325);
DISPLAY INVISIBLE (-3750 13325);
FORCEPROP 1 LAST PATH I134
J 0
(-4050 13475);
DISPLAY 0.978723 (-4050 13475);
PAINT WHITE (-4050 13475);
DISPLAY INVISIBLE (-4050 13475);
FORCEPROP 1 LAST PART_NUMBER CS00002JB13
J 0
(-4075 13275);
DISPLAY 0.319149 (-4075 13275);
DISPLAY INVISIBLE (-4075 13275);
FORCEADD Q_RES..1
(-4025 12900);
FORCEPROP 1 LAST LOCATION R1137
J 0
(-4075 12925);
DISPLAY 0.638298 (-4075 12925);
FORCEPROP 0 LAST $SEC 1
J 0
(-4075 12975);
DISPLAY 0.680851 (-4075 12975);
PAINT MONO (-4075 12975);
DISPLAY INVISIBLE (-4075 12975);
FORCEPROP 0 LAST CDS_SEC 1
J 0
(-4075 12975);
DISPLAY 0.680851 (-4075 12975);
DISPLAY INVISIBLE (-4075 12975);
FORCEPROP 1 LASTPIN (-4125 12900) $PN 1
J 0
(-4113 12912);
DISPLAY 0.787234 (-4113 12912);
PAINT MONO (-4113 12912);
FORCEPROP 1 LASTPIN (-3925 12900) $PN 2
J 0
(-3963 12912);
DISPLAY 0.787234 (-3963 12912);
PAINT MONO (-3963 12912);
FORCEPROP 0 LAST ROOM NIC_P3V3_BOM2
J 0
(-4250 12850);
DISPLAY 0.680851 (-4250 12850);
PAINT RED (-4250 12850);
FORCEPROP 1 LAST TOLERANCE 5%
J 0
(-3850 12900);
DISPLAY 0.510638 (-3850 12900);
FORCEPROP 1 LAST PACK_TYPE 0402LF
J 0
(-4250 12925);
DISPLAY 0.510638 (-4250 12925);
FORCEPROP 1 LAST MATERIAL EMPTY
J 0
(-4250 12900);
DISPLAY 0.510638 (-4250 12900);
PAINT RED (-4250 12900);
FORCEPROP 1 LAST VALUE 0
J 2
(-3875 12900);
DISPLAY 0.510638 (-3875 12900);
FORCEPROP 1 LAST WATTAGE 1/16W
J 2
(-3925 12825);
DISPLAY 0.319149 (-3925 12825);
DISPLAY INVISIBLE (-3925 12825);
FORCEPROP 2 LAST CDS_LIB pure_quanta
J 0
(-4025 12900);
DISPLAY INVISIBLE (-4025 12900);
FORCEPROP 1 LAST PATH I135
J 0
(-4075 13050);
DISPLAY 0.978723 (-4075 13050);
PAINT WHITE (-4075 13050);
DISPLAY INVISIBLE (-4075 13050);
FORCEPROP 1 LAST PART_NUMBER CS00002JB13
J 0
(-4100 12850);
DISPLAY 0.319149 (-4100 12850);
DISPLAY INVISIBLE (-4100 12850);
FORCEADD OFFPAGE..1
(-5350 13325);
PAINT AQUA (-5350 13325);
FORCEPROP 2 LAST $XR0 136 
J 0
(-5602 13325);
DISPLAY 0.638298 (-5602 13325);
PAINT MONO (-5602 13325);
FORCEPROP 2 LAST $XR1 134 
J 0
(-5722 13325);
DISPLAY 0.638298 (-5722 13325);
PAINT MONO (-5722 13325);
FORCEPROP 2 LAST $XR2 135 
J 0
(-5842 13325);
DISPLAY 0.638298 (-5842 13325);
PAINT MONO (-5842 13325);
FORCEPROP 2 LAST $XR3 248 
J 0
(-5962 13325);
DISPLAY 0.638298 (-5962 13325);
PAINT MONO (-5962 13325);
FORCEPROP 2 LAST CDS_LIB standard
J 0
(-5350 13325);
DISPLAY INVISIBLE (-5350 13325);
FORCEPROP 1 LAST OFFPAGE TRUE
J 0
(-5025 13200);
DISPLAY 0.872340 (-5025 13200);
PAINT AQUA (-5025 13200);
DISPLAY INVISIBLE (-5025 13200);
FORCEPROP 1 LAST COMMENT_BODY TRUE
J 0
(-5225 13225);
DISPLAY 0.872340 (-5225 13225);
PAINT GREEN (-5225 13225);
DISPLAY INVISIBLE (-5225 13225);
FORCEPROP 2 LAST PATH I136
J 0
(-5300 13400);
DISPLAY 0.680851 (-5300 13400);
DISPLAY INVISIBLE (-5300 13400);
FORCEADD RS31312R..1
(-6400 9475);
FORCEPROP 1 LAST LOCATION PU204
J 0
(-6647 10286);
DISPLAY 0.723404 (-6647 10286);
PAINT GREEN (-6647 10286);
FORCEPROP 2 LAST SEC 1
J 0
(-6625 10425);
DISPLAY 0.680851 (-6625 10425);
PAINT MONO (-6625 10425);
DISPLAY INVISIBLE (-6625 10425);
FORCEPROP 2 LASTPIN (-6000 9350) $PN 12
J 0
(-5990 9360);
DISPLAY 0.680851 (-5990 9360);
PAINT MONO (-5990 9360);
FORCEPROP 2 LASTPIN (-6800 9600) $PN 1
J 2
(-6810 9610);
DISPLAY 0.680851 (-6810 9610);
PAINT MONO (-6810 9610);
FORCEPROP 2 LASTPIN (-6800 9400) $PN 3
J 2
(-6810 9410);
DISPLAY 0.680851 (-6810 9410);
PAINT MONO (-6810 9410);
FORCEPROP 2 LASTPIN (-6000 9100) $PN 9
J 0
(-5990 9110);
DISPLAY 0.680851 (-5990 9110);
PAINT MONO (-5990 9110);
FORCEPROP 2 LASTPIN (-6800 9000) $PN 7
J 2
(-6810 9010);
DISPLAY 0.680851 (-6810 9010);
PAINT MONO (-6810 9010);
FORCEPROP 2 LASTPIN (-6000 9000) $PN 8
J 0
(-5990 9010);
DISPLAY 0.680851 (-5990 9010);
PAINT MONO (-5990 9010);
FORCEPROP 2 LASTPIN (-6800 9200) $PN 5
J 2
(-6810 9210);
DISPLAY 0.680851 (-6810 9210);
PAINT MONO (-6810 9210);
FORCEPROP 2 LASTPIN (-6800 9500) $PN 2
J 2
(-6810 9510);
DISPLAY 0.680851 (-6810 9510);
PAINT MONO (-6810 9510);
FORCEPROP 2 LASTPIN (-6000 9250) $PN 11
J 0
(-5990 9260);
DISPLAY 0.680851 (-5990 9260);
PAINT MONO (-5990 9260);
FORCEPROP 2 LASTPIN (-6000 9950) $PN 10
J 0
(-5990 9960);
DISPLAY 0.680851 (-5990 9960);
PAINT MONO (-5990 9960);
FORCEPROP 2 LASTPIN (-6800 9100) $PN 6
J 2
(-6810 9110);
DISPLAY 0.680851 (-6810 9110);
PAINT MONO (-6810 9110);
FORCEPROP 2 LASTPIN (-6800 9300) $PN 4
J 2
(-6810 9310);
DISPLAY 0.680851 (-6810 9310);
PAINT MONO (-6810 9310);
FORCEPROP 2 LASTPIN (-6800 9950) $PN 21_22
J 2
(-6810 9960);
DISPLAY 0.680851 (-6810 9960);
PAINT MONO (-6810 9960);
FORCEPROP 2 LASTPIN (-6800 9900) $PN 23
J 2
(-6810 9910);
DISPLAY 0.680851 (-6810 9910);
PAINT MONO (-6810 9910);
FORCEPROP 2 LASTPIN (-6800 9850) $PN 24
J 2
(-6810 9860);
DISPLAY 0.680851 (-6810 9860);
PAINT MONO (-6810 9860);
FORCEPROP 2 LASTPIN (-6800 9800) $PN 25
J 2
(-6810 9810);
DISPLAY 0.680851 (-6810 9810);
PAINT MONO (-6810 9810);
FORCEPROP 2 LASTPIN (-6800 9750) $PN 26
J 2
(-6810 9760);
DISPLAY 0.680851 (-6810 9760);
PAINT MONO (-6810 9760);
FORCEPROP 2 LASTPIN (-6000 9450) $PN 13
J 0
(-5990 9460);
DISPLAY 0.680851 (-5990 9460);
PAINT MONO (-5990 9460);
FORCEPROP 2 LASTPIN (-6000 9500) $PN 14
J 0
(-5990 9510);
DISPLAY 0.680851 (-5990 9510);
PAINT MONO (-5990 9510);
FORCEPROP 2 LASTPIN (-6000 9550) $PN 15
J 0
(-5990 9560);
DISPLAY 0.680851 (-5990 9560);
PAINT MONO (-5990 9560);
FORCEPROP 2 LASTPIN (-6000 9600) $PN 16
J 0
(-5990 9610);
DISPLAY 0.680851 (-5990 9610);
PAINT MONO (-5990 9610);
FORCEPROP 2 LASTPIN (-6000 9650) $PN 17
J 0
(-5990 9660);
DISPLAY 0.680851 (-5990 9660);
PAINT MONO (-5990 9660);
FORCEPROP 2 LASTPIN (-6000 9700) $PN 18
J 0
(-5990 9710);
DISPLAY 0.680851 (-5990 9710);
PAINT MONO (-5990 9710);
FORCEPROP 2 LASTPIN (-6000 9750) $PN 19
J 0
(-5990 9760);
DISPLAY 0.680851 (-5990 9760);
PAINT MONO (-5990 9760);
FORCEPROP 2 LASTPIN (-6000 9800) $PN 20
J 0
(-5990 9810);
DISPLAY 0.680851 (-5990 9810);
PAINT MONO (-5990 9810);
FORCEPROP 2 LAST VALUE RS31312R
J 0
(-6625 10325);
DISPLAY 0.680851 (-6625 10325);
FORCEPROP 1 LAST MATERIAL IC
J 0
(-6647 10012);
DISPLAY 0.723404 (-6647 10012);
PAINT GREEN (-6647 10012);
FORCEPROP 2 LAST PART_TYPE SMLF
J 0
(-6625 10375);
DISPLAY 0.680851 (-6625 10375);
FORCEPROP 0 LAST ROOM NIC_P12V_MPS_MAM_BOM2
J 0
(-6625 10475);
DISPLAY 0.680851 (-6625 10475);
PAINT RED (-6625 10475);
FORCEPROP 1 LAST CDS_LMAN_SYM_OUTLINE -250,525,250,-525
J 0
(-6400 9475);
DISPLAY 0.468085 (-6400 9475);
PAINT GREEN (-6400 9475);
DISPLAY INVISIBLE (-6400 9475);
FORCEPROP 1 LAST NEEDS_NO_SIZE TRUE
J 0
(-6400 9475);
DISPLAY 0.723404 (-6400 9475);
PAINT GREEN (-6400 9475);
DISPLAY INVISIBLE (-6400 9475);
FORCEPROP 2 LAST CDS_LIB pure_quanta
J 0
(-6400 9475);
DISPLAY INVISIBLE (-6400 9475);
FORCEPROP 2 LAST SEC_TYPE 
J 0
(-6625 10425);
DISPLAY 0.680851 (-6625 10425);
DISPLAY INVISIBLE (-6625 10425);
FORCEPROP 1 LAST PATH I137
J 0
(-6400 9475);
DISPLAY 0.723404 (-6400 9475);
PAINT GREEN (-6400 9475);
DISPLAY INVISIBLE (-6400 9475);
FORCEPROP 1 LAST PART_NUMBER AL031312000
J 0
(-6647 10139);
DISPLAY 0.723404 (-6647 10139);
PAINT GREEN (-6647 10139);
DISPLAY INVISIBLE (-6647 10139);
FORCEADD OFFPAGE..1
(-8550 9600);
PAINT AQUA (-8550 9600);
FORCEPROP 2 LAST $XR0 80 
J 0
(-8801 9600);
DISPLAY 0.638298 (-8801 9600);
PAINT MONO (-8801 9600);
FORCEPROP 2 LAST $XR1 83 
J 0
(-8891 9600);
DISPLAY 0.638298 (-8891 9600);
PAINT MONO (-8891 9600);
FORCEPROP 2 LAST $XR2 134 
J 0
(-9011 9600);
DISPLAY 0.638298 (-9011 9600);
PAINT MONO (-9011 9600);
FORCEPROP 2 LAST $XR3 136 
J 0
(-9131 9600);
DISPLAY 0.638298 (-9131 9600);
PAINT MONO (-9131 9600);
FORCEPROP 2 LAST CDS_LIB standard
J 0
(-8550 9600);
DISPLAY INVISIBLE (-8550 9600);
FORCEPROP 1 LAST OFFPAGE TRUE
J 0
(-8225 9475);
DISPLAY 0.872340 (-8225 9475);
PAINT AQUA (-8225 9475);
DISPLAY INVISIBLE (-8225 9475);
FORCEPROP 1 LAST COMMENT_BODY TRUE
J 0
(-8425 9500);
DISPLAY 0.872340 (-8425 9500);
PAINT GREEN (-8425 9500);
DISPLAY INVISIBLE (-8425 9500);
FORCEPROP 2 LAST PATH I58
J 0
(-8800 9650);
DISPLAY 0.680851 (-8800 9650);
DISPLAY INVISIBLE (-8800 9650);
FORCEADD GND..1
(-8025 8800);
FORCEPROP 3 LASTPIN (-8025 8850) SIG_NAME GND\g
J 0
(-8015 8860);
DISPLAY 0.659574 (-8015 8860);
PAINT MONO (-8015 8860);
DISPLAY INVISIBLE (-8015 8860);
FORCEPROP 2 LAST CDS_LIB pure_quanta_power
J 0
(-8025 8800);
DISPLAY INVISIBLE (-8025 8800);
FORCEPROP 1 LAST SIZE 1B
J 0
(-7950 8750);
DISPLAY 0.872340 (-7950 8750);
PAINT GREEN (-7950 8750);
DISPLAY INVISIBLE (-7950 8750);
FORCEPROP 1 LAST HDL_POWER GND
J 0
(-8025 8950);
DISPLAY 0.872340 (-8025 8950);
PAINT GREEN (-8025 8950);
DISPLAY INVISIBLE (-8025 8950);
FORCEPROP 1 LAST PATH I59
J 0
(-7950 8800);
DISPLAY 0.872340 (-7950 8800);
PAINT AQUA (-7950 8800);
DISPLAY INVISIBLE (-7950 8800);
FORCEADD Q_CAP..1
(-8025 9150);
FORCEPROP 1 LAST LOCATION PC2153
J 0
(-7975 9250);
DISPLAY 0.638298 (-7975 9250);
FORCEPROP 0 LAST $SEC 1
J 0
(-7975 9300);
DISPLAY INVISIBLE (-7975 9300);
FORCEPROP 0 LAST CDS_SEC 1
J 0
(-7975 9300);
DISPLAY INVISIBLE (-7975 9300);
FORCEPROP 1 LASTPIN (-8025 9250) $PN 1
J 0
(-8015 9230);
DISPLAY 0.787234 (-8015 9230);
PAINT MONO (-8015 9230);
DISPLAY INVISIBLE (-8015 9230);
FORCEPROP 1 LASTPIN (-8025 9050) $PN 2
J 0
(-8015 9030);
DISPLAY 0.787234 (-8015 9030);
PAINT MONO (-8015 9030);
DISPLAY INVISIBLE (-8015 9030);
FORCEPROP 1 LAST PACK_TYPE 0402
J 0
(-7980 9058);
DISPLAY 0.510638 (-7980 9058);
FORCEPROP 1 LAST VALUE 0.22UF
J 0
(-7975 9200);
DISPLAY 0.510638 (-7975 9200);
FORCEPROP 1 LAST VOLTAGE 16V
J 0
(-7975 9150);
DISPLAY 0.510638 (-7975 9150);
FORCEPROP 1 LAST MATERIAL X7R
J 0
(-7980 9108);
DISPLAY 0.510638 (-7980 9108);
PAINT RED (-7980 9108);
FORCEPROP 0 LAST ROOM NIC_P12V_MPS_MAM_BOM2
J 0
(-8100 8950);
DISPLAY 0.446809 (-8100 8950);
PAINT RED (-8100 8950);
FORCEPROP 1 LAST TOLERANCE 10%
J 0
(-7975 9100);
DISPLAY 0.638298 (-7975 9100);
DISPLAY INVISIBLE (-7975 9100);
FORCEPROP 2 LAST CDS_LIB pure_quanta
J 0
(-8025 9150);
DISPLAY INVISIBLE (-8025 9150);
FORCEPROP 1 LAST PATH I60
J 0
(-7975 9300);
DISPLAY 0.978723 (-7975 9300);
PAINT WHITE (-7975 9300);
DISPLAY INVISIBLE (-7975 9300);
FORCEPROP 1 LAST PART_NUMBER CH4223K1B00
J 0
(-7975 9000);
DISPLAY 0.510638 (-7975 9000);
DISPLAY INVISIBLE (-7975 9000);
FORCEADD GND..1
(-7600 8725);
FORCEPROP 3 LASTPIN (-7600 8775) SIG_NAME GND\g
J 0
(-7590 8785);
DISPLAY 0.659574 (-7590 8785);
PAINT MONO (-7590 8785);
DISPLAY INVISIBLE (-7590 8785);
FORCEPROP 2 LAST CDS_LIB pure_quanta_power
J 0
(-7600 8725);
DISPLAY INVISIBLE (-7600 8725);
FORCEPROP 1 LAST SIZE 1B
J 0
(-7525 8675);
DISPLAY 0.872340 (-7525 8675);
PAINT GREEN (-7525 8675);
DISPLAY INVISIBLE (-7525 8675);
FORCEPROP 1 LAST HDL_POWER GND
J 0
(-7600 8875);
DISPLAY 0.872340 (-7600 8875);
PAINT GREEN (-7600 8875);
DISPLAY INVISIBLE (-7600 8875);
FORCEPROP 1 LAST PATH I61
J 0
(-7525 8725);
DISPLAY 0.872340 (-7525 8725);
PAINT AQUA (-7525 8725);
DISPLAY INVISIBLE (-7525 8725);
FORCEADD GND..1
(-7200 8700);
FORCEPROP 3 LASTPIN (-7200 8750) SIG_NAME GND\g
J 0
(-7190 8760);
DISPLAY 0.659574 (-7190 8760);
PAINT MONO (-7190 8760);
DISPLAY INVISIBLE (-7190 8760);
FORCEPROP 2 LAST CDS_LIB pure_quanta_power
J 0
(-7200 8700);
DISPLAY INVISIBLE (-7200 8700);
FORCEPROP 1 LAST SIZE 1B
J 0
(-7125 8650);
DISPLAY 0.872340 (-7125 8650);
PAINT GREEN (-7125 8650);
DISPLAY INVISIBLE (-7125 8650);
FORCEPROP 1 LAST HDL_POWER GND
J 0
(-7200 8850);
DISPLAY 0.872340 (-7200 8850);
PAINT GREEN (-7200 8850);
DISPLAY INVISIBLE (-7200 8850);
FORCEPROP 1 LAST PATH I62
J 0
(-7125 8700);
DISPLAY 0.872340 (-7125 8700);
PAINT AQUA (-7125 8700);
DISPLAY INVISIBLE (-7125 8700);
FORCEADD Q_RES..2
(-7600 9025);
FORCEPROP 1 LAST LOCATION PR3835
J 0
(-7550 9150);
DISPLAY 0.638298 (-7550 9150);
FORCEPROP 0 LAST $SEC 1
J 0
(-7550 9175);
DISPLAY 0.680851 (-7550 9175);
PAINT MONO (-7550 9175);
DISPLAY INVISIBLE (-7550 9175);
FORCEPROP 0 LAST CDS_SEC 1
J 0
(-7550 9150);
DISPLAY INVISIBLE (-7550 9150);
FORCEPROP 1 LASTPIN (-7600 9125) $PN 1
J 0
(-7595 9087);
DISPLAY 0.787234 (-7595 9087);
PAINT MONO (-7595 9087);
FORCEPROP 1 LASTPIN (-7600 8925) $PN 2
J 0
(-7595 8935);
DISPLAY 0.787234 (-7595 8935);
PAINT MONO (-7595 8935);
FORCEPROP 0 LAST ROOM NIC_P12V_MPS_MAM_BOM2
J 0
(-7650 8800);
DISPLAY 0.446809 (-7650 8800);
PAINT RED (-7650 8800);
FORCEPROP 1 LAST WATTAGE 1/16W
J 0
(-7560 9000);
DISPLAY 0.510638 (-7560 9000);
FORCEPROP 1 LAST PACK_TYPE 0402LF
J 0
(-7560 8850);
DISPLAY 0.510638 (-7560 8850);
FORCEPROP 1 LAST TOLERANCE 1%
J 0
(-7555 9050);
DISPLAY 0.510638 (-7555 9050);
FORCEPROP 1 LAST VALUE 14.3K
J 0
(-7555 9100);
DISPLAY 0.510638 (-7555 9100);
FORCEPROP 1 LAST MATERIAL CHIP
J 0
(-7560 8950);
DISPLAY 0.510638 (-7560 8950);
PAINT RED (-7560 8950);
FORCEPROP 2 LAST CDS_LIB pure_quanta
J 0
(-7600 9025);
DISPLAY INVISIBLE (-7600 9025);
FORCEPROP 1 LAST PATH I63
J 0
(-7550 9200);
DISPLAY 0.978723 (-7550 9200);
PAINT WHITE (-7550 9200);
DISPLAY INVISIBLE (-7550 9200);
FORCEPROP 1 LAST PART_NUMBER CS31432FB02
J 0
(-7560 8900);
DISPLAY 0.510638 (-7560 8900);
DISPLAY INVISIBLE (-7560 8900);
FORCEADD Q_CAP..1
(-7200 8925);
FORCEPROP 1 LAST LOCATION PC2155
J 0
(-7150 9025);
DISPLAY 0.638298 (-7150 9025);
FORCEPROP 0 LAST $SEC 1
J 0
(-7150 9075);
DISPLAY INVISIBLE (-7150 9075);
FORCEPROP 0 LAST CDS_SEC 1
J 0
(-7150 9075);
DISPLAY INVISIBLE (-7150 9075);
FORCEPROP 1 LASTPIN (-7200 9025) $PN 1
J 0
(-7190 9005);
DISPLAY 0.787234 (-7190 9005);
PAINT MONO (-7190 9005);
DISPLAY INVISIBLE (-7190 9005);
FORCEPROP 1 LASTPIN (-7200 8825) $PN 2
J 0
(-7190 8805);
DISPLAY 0.787234 (-7190 8805);
PAINT MONO (-7190 8805);
DISPLAY INVISIBLE (-7190 8805);
FORCEPROP 1 LAST PACK_TYPE C0402
J 0
(-7158 8824);
DISPLAY 0.510638 (-7158 8824);
FORCEPROP 1 LAST VOLTAGE 25V
J 0
(-7158 8874);
DISPLAY 0.510638 (-7158 8874);
FORCEPROP 1 LAST MATERIAL X7R
J 0
(-7158 8924);
DISPLAY 0.510638 (-7158 8924);
PAINT RED (-7158 8924);
FORCEPROP 1 LAST VALUE 0.047UF
J 0
(-7150 8975);
DISPLAY 0.510638 (-7150 8975);
FORCEPROP 0 LAST ROOM NIC_P12V_MPS_MAM_BOM2
J 0
(-7150 8725);
DISPLAY 0.553191 (-7150 8725);
PAINT RED (-7150 8725);
FORCEPROP 1 LAST TOLERANCE 10%
J 0
(-7150 8875);
DISPLAY 0.638298 (-7150 8875);
DISPLAY INVISIBLE (-7150 8875);
FORCEPROP 2 LAST CDS_LIB pure_quanta
J 0
(-7200 8925);
DISPLAY INVISIBLE (-7200 8925);
FORCEPROP 1 LAST PATH I64
J 0
(-7150 9075);
DISPLAY 0.978723 (-7150 9075);
PAINT WHITE (-7150 9075);
DISPLAY INVISIBLE (-7150 9075);
FORCEPROP 1 LAST PART_NUMBER CH3474K1B04
J 0
(-7158 8774);
DISPLAY 0.510638 (-7158 8774);
DISPLAY INVISIBLE (-7158 8774);
FORCEADD GND..1
(-7600 9350);
FORCEPROP 3 LASTPIN (-7600 9400) SIG_NAME GND\g
J 0
(-7590 9410);
DISPLAY 0.659574 (-7590 9410);
PAINT MONO (-7590 9410);
DISPLAY INVISIBLE (-7590 9410);
FORCEPROP 1 LAST SIZE 1B
J 0
(-7525 9300);
DISPLAY 0.872340 (-7525 9300);
PAINT GREEN (-7525 9300);
DISPLAY INVISIBLE (-7525 9300);
FORCEPROP 2 LAST CDS_LIB pure_quanta_power
J 0
(-7600 9350);
DISPLAY INVISIBLE (-7600 9350);
FORCEPROP 1 LAST HDL_POWER GND
J 0
(-7600 9500);
DISPLAY 0.872340 (-7600 9500);
PAINT GREEN (-7600 9500);
DISPLAY INVISIBLE (-7600 9500);
FORCEPROP 1 LAST PATH I66
J 0
(-7525 9350);
DISPLAY 0.872340 (-7525 9350);
PAINT AQUA (-7525 9350);
DISPLAY INVISIBLE (-7525 9350);
FORCEADD GND..1
(-7275 9775);
FORCEPROP 3 LASTPIN (-7275 9825) SIG_NAME GND\g
J 0
(-7265 9835);
DISPLAY 0.659574 (-7265 9835);
PAINT MONO (-7265 9835);
DISPLAY INVISIBLE (-7265 9835);
FORCEPROP 2 LAST CDS_LIB pure_quanta_power
J 0
(-7275 9775);
DISPLAY INVISIBLE (-7275 9775);
FORCEPROP 1 LAST SIZE 1B
J 0
(-7200 9725);
DISPLAY 0.872340 (-7200 9725);
PAINT GREEN (-7200 9725);
DISPLAY INVISIBLE (-7200 9725);
FORCEPROP 1 LAST HDL_POWER GND
J 0
(-7275 9925);
DISPLAY 0.872340 (-7275 9925);
PAINT GREEN (-7275 9925);
DISPLAY INVISIBLE (-7275 9925);
FORCEPROP 1 LAST PATH I67
J 0
(-7200 9775);
DISPLAY 0.872340 (-7200 9775);
PAINT AQUA (-7200 9775);
DISPLAY INVISIBLE (-7200 9775);
FORCEADD Q_CAP..1
(-7275 10000);
FORCEPROP 1 LAST LOCATION PC2154
J 0
(-7225 10100);
DISPLAY 0.638298 (-7225 10100);
FORCEPROP 0 LAST $SEC 1
J 0
(-7220 10142);
DISPLAY INVISIBLE (-7220 10142);
FORCEPROP 0 LAST CDS_SEC 1
J 0
(-7220 10142);
DISPLAY INVISIBLE (-7220 10142);
FORCEPROP 1 LASTPIN (-7275 10100) $PN 1
J 0
(-7265 10080);
DISPLAY 0.787234 (-7265 10080);
PAINT MONO (-7265 10080);
DISPLAY INVISIBLE (-7265 10080);
FORCEPROP 1 LASTPIN (-7275 9900) $PN 2
J 0
(-7265 9880);
DISPLAY 0.787234 (-7265 9880);
PAINT MONO (-7265 9880);
DISPLAY INVISIBLE (-7265 9880);
FORCEPROP 1 LAST VALUE 1UF
J 0
(-7225 10050);
DISPLAY 0.510638 (-7225 10050);
FORCEPROP 1 LAST MATERIAL X6S
J 0
(-7225 9950);
DISPLAY 0.510638 (-7225 9950);
PAINT RED (-7225 9950);
FORCEPROP 1 LAST VOLTAGE 25V
J 0
(-7225 10000);
DISPLAY 0.510638 (-7225 10000);
FORCEPROP 1 LAST PACK_TYPE C0402
J 0
(-7225 9900);
DISPLAY 0.510638 (-7225 9900);
FORCEPROP 0 LAST ROOM NIC_P12V_MPS_MAM_BOM2
J 0
(-7350 10150);
DISPLAY 0.446809 (-7350 10150);
PAINT RED (-7350 10150);
FORCEPROP 1 LAST TOLERANCE 10%
J 0
(-7225 9950);
DISPLAY 0.638298 (-7225 9950);
DISPLAY INVISIBLE (-7225 9950);
FORCEPROP 2 LAST CDS_LIB pure_quanta
J 0
(-7275 10000);
DISPLAY INVISIBLE (-7275 10000);
FORCEPROP 1 LAST PATH I68
J 0
(-7225 10150);
DISPLAY 0.978723 (-7225 10150);
PAINT WHITE (-7225 10150);
DISPLAY INVISIBLE (-7225 10150);
FORCEPROP 1 LAST PART_NUMBER CH5104KEB02
J 0
(-7225 9850);
DISPLAY 0.510638 (-7225 9850);
DISPLAY INVISIBLE (-7225 9850);
FORCEADD UNIVERSAL_POWER..1
(-7275 10350);
FORCEPROP 3 LASTPIN (-7275 10300) SIG_NAME P12V_AUX\g
J 0
(-7265 10310);
DISPLAY 0.659574 (-7265 10310);
PAINT MONO (-7265 10310);
DISPLAY INVISIBLE (-7265 10310);
FORCEPROP 1 LAST HDL_POWER P12V_AUX
J 1
(-7275 10400);
DISPLAY 0.872340 (-7275 10400);
PAINT GREEN (-7275 10400);
FORCEPROP 2 LAST CDS_LIB pure_quanta_power
J 0
(-7275 10350);
DISPLAY INVISIBLE (-7275 10350);
FORCEPROP 1 LAST PATH I69
J 0
(-7225 10375);
DISPLAY 0.872340 (-7225 10375);
PAINT AQUA (-7225 10375);
DISPLAY INVISIBLE (-7225 10375);
FORCEADD GND..1
(-6859 8866);
FORCEPROP 3 LASTPIN (-6859 8916) SIG_NAME GND\g
J 0
(-6849 8926);
DISPLAY 0.659574 (-6849 8926);
PAINT MONO (-6849 8926);
DISPLAY INVISIBLE (-6849 8926);
FORCEPROP 2 LAST CDS_LIB pure_quanta_power
J 0
(-6859 8866);
DISPLAY INVISIBLE (-6859 8866);
FORCEPROP 1 LAST SIZE 1B
J 0
(-6784 8816);
DISPLAY 0.872340 (-6784 8816);
PAINT GREEN (-6784 8816);
DISPLAY INVISIBLE (-6784 8816);
FORCEPROP 1 LAST HDL_POWER GND
J 0
(-6859 9016);
DISPLAY 0.872340 (-6859 9016);
PAINT GREEN (-6859 9016);
DISPLAY INVISIBLE (-6859 9016);
FORCEPROP 1 LAST PATH I70
J 0
(-6784 8866);
DISPLAY 0.872340 (-6784 8866);
PAINT AQUA (-6784 8866);
DISPLAY INVISIBLE (-6784 8866);
FORCEADD Q_RES..2
(-5775 8725);
FORCEPROP 1 LAST LOCATION PR3837
J 0
(-5730 8850);
DISPLAY 0.638298 (-5730 8850);
FORCEPROP 0 LAST $SEC 1
J 0
(-5725 8900);
DISPLAY 0.680851 (-5725 8900);
PAINT MONO (-5725 8900);
DISPLAY INVISIBLE (-5725 8900);
FORCEPROP 0 LAST CDS_SEC 1
J 0
(-5725 8900);
DISPLAY 1.021277 (-5725 8900);
DISPLAY INVISIBLE (-5725 8900);
FORCEPROP 1 LASTPIN (-5775 8825) $PN 1
J 0
(-5770 8787);
DISPLAY 0.787234 (-5770 8787);
PAINT MONO (-5770 8787);
FORCEPROP 1 LASTPIN (-5775 8625) $PN 2
J 0
(-5770 8635);
DISPLAY 0.787234 (-5770 8635);
PAINT MONO (-5770 8635);
FORCEPROP 1 LAST WATTAGE 1/16W
J 0
(-5735 8700);
DISPLAY 0.510638 (-5735 8700);
FORCEPROP 1 LAST PACK_TYPE 0402LF
J 0
(-5735 8550);
DISPLAY 0.510638 (-5735 8550);
FORCEPROP 1 LAST VALUE 17.4K
J 0
(-5730 8800);
DISPLAY 0.510638 (-5730 8800);
FORCEPROP 1 LAST TOLERANCE 1%
J 0
(-5730 8750);
DISPLAY 0.510638 (-5730 8750);
FORCEPROP 1 LAST MATERIAL CHIP
J 0
(-5735 8650);
DISPLAY 0.510638 (-5735 8650);
PAINT RED (-5735 8650);
FORCEPROP 0 LAST ROOM NIC_P12V_MPS_MAM_BOM2
J 0
(-5850 8500);
DISPLAY 0.446809 (-5850 8500);
PAINT RED (-5850 8500);
FORCEPROP 2 LAST CDS_LIB pure_quanta
J 0
(-5775 8725);
DISPLAY INVISIBLE (-5775 8725);
FORCEPROP 1 LAST PATH I71
J 0
(-5725 8900);
DISPLAY 0.978723 (-5725 8900);
PAINT WHITE (-5725 8900);
DISPLAY INVISIBLE (-5725 8900);
FORCEPROP 1 LAST PART_NUMBER CS31742FB04
J 0
(-5735 8600);
DISPLAY 0.510638 (-5735 8600);
DISPLAY INVISIBLE (-5735 8600);
FORCEADD GND..1
(-5325 8325);
FORCEPROP 3 LASTPIN (-5325 8375) SIG_NAME GND\g
J 0
(-5315 8385);
DISPLAY 0.659574 (-5315 8385);
PAINT MONO (-5315 8385);
DISPLAY INVISIBLE (-5315 8385);
FORCEPROP 1 LAST SIZE 1B
J 0
(-5250 8275);
DISPLAY 0.872340 (-5250 8275);
PAINT GREEN (-5250 8275);
DISPLAY INVISIBLE (-5250 8275);
FORCEPROP 2 LAST CDS_LIB pure_quanta_power
J 0
(-5325 8325);
DISPLAY INVISIBLE (-5325 8325);
FORCEPROP 1 LAST HDL_POWER GND
J 0
(-5325 8475);
DISPLAY 0.872340 (-5325 8475);
PAINT GREEN (-5325 8475);
DISPLAY INVISIBLE (-5325 8475);
FORCEPROP 1 LAST PATH I72
J 0
(-5250 8325);
DISPLAY 0.872340 (-5250 8325);
PAINT AQUA (-5250 8325);
DISPLAY INVISIBLE (-5250 8325);
FORCEADD Q_CAP..1
(-5325 8725);
FORCEPROP 1 LAST LOCATION PC2156
J 0
(-5275 8825);
DISPLAY 0.638298 (-5275 8825);
FORCEPROP 0 LAST $SEC 1
J 0
(-5275 8875);
DISPLAY INVISIBLE (-5275 8875);
FORCEPROP 0 LAST CDS_SEC 1
J 0
(-5275 8875);
DISPLAY INVISIBLE (-5275 8875);
FORCEPROP 1 LASTPIN (-5325 8825) $PN 1
J 0
(-5315 8805);
DISPLAY 0.787234 (-5315 8805);
PAINT MONO (-5315 8805);
DISPLAY INVISIBLE (-5315 8805);
FORCEPROP 1 LASTPIN (-5325 8625) $PN 2
J 0
(-5315 8605);
DISPLAY 0.787234 (-5315 8605);
PAINT MONO (-5315 8605);
DISPLAY INVISIBLE (-5315 8605);
FORCEPROP 1 LAST VOLTAGE 50V
J 0
(-5270 8717);
DISPLAY 0.638298 (-5270 8717);
FORCEPROP 1 LAST PACK_TYPE C0402
J 0
(-5270 8667);
DISPLAY 0.638298 (-5270 8667);
FORCEPROP 1 LAST MATERIAL X7R
J 0
(-5250 8550);
DISPLAY 0.638298 (-5250 8550);
PAINT RED (-5250 8550);
FORCEPROP 0 LAST ROOM NIC_P12V_MPS_MAM_BOM2
J 0
(-5300 8500);
DISPLAY 0.446809 (-5300 8500);
PAINT RED (-5300 8500);
FORCEPROP 1 LAST VALUE 100NF
J 0
(-5275 8775);
DISPLAY 0.638298 (-5275 8775);
FORCEPROP 1 LAST TOLERANCE 10%
J 0
(-5275 8675);
DISPLAY 0.638298 (-5275 8675);
DISPLAY INVISIBLE (-5275 8675);
FORCEPROP 2 LAST CDS_LIB pure_quanta
J 0
(-5325 8725);
DISPLAY INVISIBLE (-5325 8725);
FORCEPROP 1 LAST PATH I73
J 0
(-5275 8875);
DISPLAY 0.978723 (-5275 8875);
PAINT WHITE (-5275 8875);
DISPLAY INVISIBLE (-5275 8875);
FORCEPROP 1 LAST PART_NUMBER CH4106K1B01
J 0
(-5270 8617);
DISPLAY 0.638298 (-5270 8617);
DISPLAY INVISIBLE (-5270 8617);
FORCEADD Q_RES..1
(-5400 9100);
FORCEPROP 1 LAST LOCATION PR3839
J 0
(-5475 9150);
DISPLAY 0.638298 (-5475 9150);
FORCEPROP 0 LAST $SEC 1
J 0
(-5500 9175);
DISPLAY 0.680851 (-5500 9175);
PAINT MONO (-5500 9175);
DISPLAY INVISIBLE (-5500 9175);
FORCEPROP 0 LAST CDS_SEC 1
J 0
(-5450 9250);
DISPLAY INVISIBLE (-5450 9250);
FORCEPROP 1 LASTPIN (-5500 9100) $PN 1
J 0
(-5488 9112);
DISPLAY 0.787234 (-5488 9112);
PAINT MONO (-5488 9112);
DISPLAY INVISIBLE (-5488 9112);
FORCEPROP 1 LASTPIN (-5300 9100) $PN 2
J 0
(-5338 9112);
DISPLAY 0.787234 (-5338 9112);
PAINT MONO (-5338 9112);
DISPLAY INVISIBLE (-5338 9112);
FORCEPROP 1 LAST MATERIAL CHIP
J 0
(-5275 9075);
DISPLAY 0.404255 (-5275 9075);
PAINT RED (-5275 9075);
FORCEPROP 1 LAST TOLERANCE 1%
J 0
(-5350 9075);
DISPLAY 0.510638 (-5350 9075);
FORCEPROP 1 LAST VALUE 10K
J 2
(-5425 9075);
DISPLAY 0.510638 (-5425 9075);
FORCEPROP 1 LAST PACK_TYPE 0402LF
J 0
(-5250 9125);
DISPLAY 0.404255 (-5250 9125);
FORCEPROP 0 LAST ROOM NIC_P12V_MPS_MAM_BOM2
J 0
(-5600 9050);
DISPLAY 0.446809 (-5600 9050);
PAINT RED (-5600 9050);
FORCEPROP 1 LAST WATTAGE 1/16W
J 2
(-5075 9075);
DISPLAY 0.404255 (-5075 9075);
FORCEPROP 2 LAST CDS_LIB pure_quanta
J 0
(-5400 9100);
DISPLAY INVISIBLE (-5400 9100);
FORCEPROP 1 LAST PATH I74
J 0
(-5450 9250);
DISPLAY 0.978723 (-5450 9250);
PAINT WHITE (-5450 9250);
DISPLAY INVISIBLE (-5450 9250);
FORCEPROP 1 LAST PART_NUMBER CS31002FB08
J 0
(-5500 9125);
DISPLAY 0.404255 (-5500 9125);
DISPLAY INVISIBLE (-5500 9125);
FORCEADD Q_RES..2
(-5925 10175);
FORCEPROP 1 LAST LOCATION R4532
J 0
(-5850 10200);
DISPLAY 0.638298 (-5850 10200);
FORCEPROP 0 LAST $SEC 1
J 0
(-5870 10392);
DISPLAY 0.680851 (-5870 10392);
PAINT MONO (-5870 10392);
DISPLAY INVISIBLE (-5870 10392);
FORCEPROP 0 LAST CDS_SEC 1
J 0
(-5875 10350);
DISPLAY INVISIBLE (-5875 10350);
FORCEPROP 1 LASTPIN (-5925 10275) $PN 1
J 0
(-5920 10237);
DISPLAY 0.787234 (-5920 10237);
PAINT MONO (-5920 10237);
FORCEPROP 1 LASTPIN (-5925 10075) $PN 2
J 0
(-5920 10085);
DISPLAY 0.787234 (-5920 10085);
PAINT MONO (-5920 10085);
FORCEPROP 0 LAST ROOM NIC_P12V_MPS_MAM_BOM2
J 0
(-5850 10250);
DISPLAY 0.553191 (-5850 10250);
PAINT RED (-5850 10250);
FORCEPROP 1 LAST TOLERANCE 1%
J 0
(-5850 10150);
DISPLAY 0.638298 (-5850 10150);
FORCEPROP 1 LAST MATERIAL CHIP
J 0
(-5850 10100);
DISPLAY 0.638298 (-5850 10100);
PAINT RED (-5850 10100);
FORCEPROP 1 LAST WATTAGE 1/16W
J 0
(-5850 10125);
DISPLAY 0.638298 (-5850 10125);
FORCEPROP 1 LAST VALUE 10K
J 0
(-5850 10175);
DISPLAY 0.638298 (-5850 10175);
FORCEPROP 1 LAST PACK_TYPE 0402LF
J 0
(-5850 10050);
DISPLAY 0.638298 (-5850 10050);
FORCEPROP 2 LAST CDS_LIB pure_quanta
J 0
(-5925 10175);
DISPLAY INVISIBLE (-5925 10175);
FORCEPROP 1 LAST PATH I75
J 0
(-5875 10350);
DISPLAY 0.978723 (-5875 10350);
PAINT WHITE (-5875 10350);
DISPLAY INVISIBLE (-5875 10350);
FORCEPROP 1 LAST PART_NUMBER CS31002FB08
J 0
(-5850 10075);
DISPLAY 0.638298 (-5850 10075);
DISPLAY INVISIBLE (-5850 10075);
FORCEADD Q_RES..2
(-5400 9575);
FORCEPROP 1 LAST LOCATION PR3838
J 0
(-5350 9700);
DISPLAY 0.638298 (-5350 9700);
FORCEPROP 0 LAST $SEC 1
J 0
(-5350 9750);
DISPLAY 0.680851 (-5350 9750);
PAINT MONO (-5350 9750);
DISPLAY INVISIBLE (-5350 9750);
FORCEPROP 0 LAST CDS_SEC 1
J 0
(-5350 9750);
DISPLAY 1.021277 (-5350 9750);
DISPLAY INVISIBLE (-5350 9750);
FORCEPROP 1 LASTPIN (-5400 9675) $PN 1
J 0
(-5395 9637);
DISPLAY 0.787234 (-5395 9637);
PAINT MONO (-5395 9637);
FORCEPROP 1 LASTPIN (-5400 9475) $PN 2
J 0
(-5395 9485);
DISPLAY 0.787234 (-5395 9485);
PAINT MONO (-5395 9485);
FORCEPROP 1 LAST WATTAGE 1/16W
J 0
(-5360 9550);
DISPLAY 0.510638 (-5360 9550);
FORCEPROP 1 LAST TOLERANCE 1%
J 0
(-5355 9600);
DISPLAY 0.510638 (-5355 9600);
FORCEPROP 1 LAST VALUE 100
J 0
(-5355 9650);
DISPLAY 0.510638 (-5355 9650);
FORCEPROP 1 LAST MATERIAL EMPTY
J 0
(-5360 9500);
DISPLAY 0.510638 (-5360 9500);
PAINT RED (-5360 9500);
FORCEPROP 1 LAST PACK_TYPE 0402LF
J 0
(-5360 9450);
DISPLAY 0.510638 (-5360 9450);
FORCEPROP 0 LAST ROOM NIC_P12V_MPS_MAM_BOM2
J 0
(-5350 9750);
DISPLAY 0.446809 (-5350 9750);
PAINT RED (-5350 9750);
FORCEPROP 2 LAST CDS_LIB pure_quanta
J 0
(-5400 9575);
DISPLAY INVISIBLE (-5400 9575);
FORCEPROP 1 LAST PATH I76
J 0
(-5350 9750);
DISPLAY 0.978723 (-5350 9750);
PAINT WHITE (-5350 9750);
DISPLAY INVISIBLE (-5350 9750);
FORCEPROP 1 LAST PART_NUMBER CS11002FB07
J 0
(-5360 9400);
DISPLAY 0.510638 (-5360 9400);
DISPLAY INVISIBLE (-5360 9400);
FORCEADD OFFPAGE..1
R 2
(-5200 9350);
PAINT AQUA (-5200 9350);
FORCEPROP 2 LAST $XR0 135 
J 0
(-5014 9350);
DISPLAY 0.638298 (-5014 9350);
PAINT MONO (-5014 9350);
FORCEPROP 2 LAST CDS_LIB standard
J 2
(-5200 9350);
DISPLAY INVISIBLE (-5200 9350);
FORCEPROP 1 LAST OFFPAGE TRUE
J 2
(-5525 9225);
DISPLAY 0.872340 (-5525 9225);
PAINT AQUA (-5525 9225);
DISPLAY INVISIBLE (-5525 9225);
FORCEPROP 1 LAST COMMENT_BODY TRUE
J 2
(-5325 9250);
DISPLAY 0.872340 (-5325 9250);
PAINT GREEN (-5325 9250);
DISPLAY INVISIBLE (-5325 9250);
FORCEPROP 2 LAST PATH I77
J 0
(-5000 9400);
DISPLAY 0.680851 (-5000 9400);
DISPLAY INVISIBLE (-5000 9400);
FORCEADD OFFPAGE..2
(-5125 9950);
PAINT AQUA (-5125 9950);
FORCEPROP 2 LAST $XR0 134 
J 0
(-4936 9950);
DISPLAY 0.638298 (-4936 9950);
PAINT MONO (-4936 9950);
FORCEPROP 2 LAST $XR1 135 
J 0
(-4936 9914);
DISPLAY 0.638298 (-4936 9914);
PAINT MONO (-4936 9914);
FORCEPROP 2 LAST $XR2 136 
J 0
(-4936 9986);
DISPLAY 0.638298 (-4936 9986);
PAINT MONO (-4936 9986);
FORCEPROP 2 LAST $XR3 248 
J 0
(-4936 9878);
DISPLAY 0.638298 (-4936 9878);
PAINT MONO (-4936 9878);
FORCEPROP 2 LAST CDS_LIB standard
J 0
(-5125 9950);
DISPLAY INVISIBLE (-5125 9950);
FORCEPROP 1 LAST OFFPAGE TRUE
J 0
(-4800 9825);
DISPLAY 0.872340 (-4800 9825);
PAINT AQUA (-4800 9825);
DISPLAY INVISIBLE (-4800 9825);
FORCEPROP 1 LAST COMMENT_BODY TRUE
J 0
(-5170 9855);
DISPLAY 0.872340 (-5170 9855);
PAINT GREEN (-5170 9855);
DISPLAY INVISIBLE (-5170 9855);
FORCEPROP 2 LAST PATH I78
J 0
(-4925 10025);
DISPLAY 0.680851 (-4925 10025);
DISPLAY INVISIBLE (-4925 10025);
FORCEADD GND..1
(-4200 8750);
FORCEPROP 3 LASTPIN (-4200 8800) SIG_NAME GND\g
J 0
(-4190 8810);
DISPLAY 0.659574 (-4190 8810);
PAINT MONO (-4190 8810);
DISPLAY INVISIBLE (-4190 8810);
FORCEPROP 1 LAST SIZE 1B
J 0
(-4125 8700);
DISPLAY 0.872340 (-4125 8700);
PAINT GREEN (-4125 8700);
DISPLAY INVISIBLE (-4125 8700);
FORCEPROP 2 LAST CDS_LIB pure_quanta_power
J 0
(-4200 8750);
DISPLAY INVISIBLE (-4200 8750);
FORCEPROP 1 LAST HDL_POWER GND
J 0
(-4200 8900);
DISPLAY 0.872340 (-4200 8900);
PAINT GREEN (-4200 8900);
DISPLAY INVISIBLE (-4200 8900);
FORCEPROP 1 LAST PATH I79
J 0
(-4125 8750);
DISPLAY 0.872340 (-4125 8750);
PAINT AQUA (-4125 8750);
DISPLAY INVISIBLE (-4125 8750);
FORCEADD Q_RES..2
(-4400 9075);
FORCEPROP 1 LAST LOCATION PR3842
J 0
(-4355 9200);
DISPLAY 0.638298 (-4355 9200);
FORCEPROP 0 LAST $SEC 1
J 0
(-4350 9250);
DISPLAY INVISIBLE (-4350 9250);
FORCEPROP 0 LAST CDS_SEC 1
J 0
(-4350 9250);
DISPLAY INVISIBLE (-4350 9250);
FORCEPROP 1 LASTPIN (-4400 9175) $PN 1
J 0
(-4395 9137);
DISPLAY 0.787234 (-4395 9137);
PAINT MONO (-4395 9137);
DISPLAY INVISIBLE (-4395 9137);
FORCEPROP 1 LASTPIN (-4400 8975) $PN 2
J 0
(-4395 8985);
DISPLAY 0.787234 (-4395 8985);
PAINT MONO (-4395 8985);
DISPLAY INVISIBLE (-4395 8985);
FORCEPROP 0 LAST ROOM NIC_P12V_MPS_MAM_BOM2
J 0
(-4375 8875);
DISPLAY 0.446809 (-4375 8875);
PAINT RED (-4375 8875);
FORCEPROP 1 LAST VALUE 10K
J 0
(-4355 9150);
DISPLAY 0.638298 (-4355 9150);
FORCEPROP 1 LAST MATERIAL CHIP
J 0
(-4360 9000);
DISPLAY 0.638298 (-4360 9000);
PAINT RED (-4360 9000);
FORCEPROP 1 LAST TOLERANCE 1%
J 0
(-4355 9100);
DISPLAY 0.638298 (-4355 9100);
FORCEPROP 1 LAST WATTAGE 1/16W
J 0
(-4360 9050);
DISPLAY 0.638298 (-4360 9050);
FORCEPROP 1 LAST PACK_TYPE 0402LF
J 0
(-4360 8900);
DISPLAY 0.638298 (-4360 8900);
FORCEPROP 2 LAST CDS_LIB pure_quanta
J 0
(-4400 9075);
DISPLAY INVISIBLE (-4400 9075);
FORCEPROP 1 LAST PATH I80
J 0
(-4350 9250);
DISPLAY 0.978723 (-4350 9250);
PAINT WHITE (-4350 9250);
DISPLAY INVISIBLE (-4350 9250);
FORCEPROP 1 LAST PART_NUMBER CS31002FB08
J 0
(-4360 8950);
DISPLAY 0.638298 (-4360 8950);
DISPLAY INVISIBLE (-4360 8950);
FORCEADD Q_RES..2
(-4800 9575);
FORCEPROP 1 LAST LOCATION PR3840
J 0
(-4775 9650);
DISPLAY 0.723404 (-4775 9650);
PAINT AQUA (-4775 9650);
FORCEPROP 0 LAST $SEC 1
J 0
(-4775 9700);
DISPLAY 0.680851 (-4775 9700);
PAINT MONO (-4775 9700);
DISPLAY INVISIBLE (-4775 9700);
FORCEPROP 0 LAST CDS_SEC 1
J 0
(-4775 9700);
DISPLAY 1.021277 (-4775 9700);
DISPLAY INVISIBLE (-4775 9700);
FORCEPROP 1 LASTPIN (-4800 9675) $PN 1
J 0
(-4795 9637);
DISPLAY 0.787234 (-4795 9637);
PAINT MONO (-4795 9637);
FORCEPROP 1 LASTPIN (-4800 9475) $PN 2
J 0
(-4795 9485);
DISPLAY 0.787234 (-4795 9485);
PAINT MONO (-4795 9485);
FORCEPROP 1 LAST MATERIAL EMPTY
J 0
(-4775 9400);
DISPLAY 0.723404 (-4775 9400);
PAINT RED (-4775 9400);
FORCEPROP 1 LAST VALUE 71.5K
J 0
(-4775 9600);
DISPLAY 0.574468 (-4775 9600);
PAINT SKYBLUE (-4775 9600);
FORCEPROP 0 LAST ROOM NIC_P12V_MPS_MAM_BOM2
J 0
(-4775 9725);
DISPLAY 0.446809 (-4775 9725);
PAINT RED (-4775 9725);
FORCEPROP 1 LAST TOLERANCE 1%
J 0
(-4775 9550);
DISPLAY 0.574468 (-4775 9550);
PAINT SKYBLUE (-4775 9550);
FORCEPROP 1 LAST PACK_TYPE 0402LF
J 0
(-4775 9500);
DISPLAY 0.574468 (-4775 9500);
PAINT SKYBLUE (-4775 9500);
FORCEPROP 2 LAST CDS_LIB pure_quanta
J 0
(-4800 9575);
DISPLAY INVISIBLE (-4800 9575);
FORCEPROP 1 LAST WATTAGE 1/16W
J 0
(-4775 9550);
DISPLAY 0.723404 (-4775 9550);
PAINT SKYBLUE (-4775 9550);
DISPLAY INVISIBLE (-4775 9550);
FORCEPROP 1 LAST PATH I81
J 0
(-4750 9750);
DISPLAY 0.978723 (-4750 9750);
PAINT WHITE (-4750 9750);
DISPLAY INVISIBLE (-4750 9750);
FORCEPROP 1 LAST PART_NUMBER CS37152FB05
J 0
(-4775 9450);
DISPLAY 0.468085 (-4775 9450);
PAINT WHITE (-4775 9450);
DISPLAY INVISIBLE (-4775 9450);
FORCEADD Q_RES..2
(-4400 9500);
FORCEPROP 1 LAST LOCATION PR3841
J 0
(-4355 9625);
DISPLAY 0.638298 (-4355 9625);
FORCEPROP 0 LAST $SEC 1
J 0
(-4350 9675);
DISPLAY INVISIBLE (-4350 9675);
FORCEPROP 0 LAST CDS_SEC 1
J 0
(-4350 9675);
DISPLAY INVISIBLE (-4350 9675);
FORCEPROP 1 LASTPIN (-4400 9600) $PN 1
J 0
(-4395 9562);
DISPLAY 0.787234 (-4395 9562);
PAINT MONO (-4395 9562);
DISPLAY INVISIBLE (-4395 9562);
FORCEPROP 1 LASTPIN (-4400 9400) $PN 2
J 0
(-4395 9410);
DISPLAY 0.787234 (-4395 9410);
PAINT MONO (-4395 9410);
DISPLAY INVISIBLE (-4395 9410);
FORCEPROP 1 LAST VALUE 120K
J 0
(-4355 9575);
DISPLAY 0.638298 (-4355 9575);
FORCEPROP 1 LAST WATTAGE 1/16W
J 0
(-4360 9475);
DISPLAY 0.638298 (-4360 9475);
FORCEPROP 0 LAST ROOM NIC_P12V_MPS_MAM_BOM2
J 0
(-4350 9300);
DISPLAY 0.446809 (-4350 9300);
PAINT RED (-4350 9300);
FORCEPROP 1 LAST PACK_TYPE 0402LF
J 0
(-4360 9325);
DISPLAY 0.638298 (-4360 9325);
FORCEPROP 1 LAST MATERIAL CHIP
J 0
(-4360 9425);
DISPLAY 0.638298 (-4360 9425);
PAINT RED (-4360 9425);
FORCEPROP 1 LAST TOLERANCE 1%
J 0
(-4355 9525);
DISPLAY 0.638298 (-4355 9525);
FORCEPROP 2 LAST CDS_LIB pure_quanta
J 0
(-4400 9500);
DISPLAY INVISIBLE (-4400 9500);
FORCEPROP 1 LAST PATH I82
J 0
(-4350 9675);
DISPLAY 0.978723 (-4350 9675);
PAINT WHITE (-4350 9675);
DISPLAY INVISIBLE (-4350 9675);
FORCEPROP 1 LAST PART_NUMBER CS41202FB05
J 0
(-4360 9375);
DISPLAY 0.638298 (-4360 9375);
DISPLAY INVISIBLE (-4360 9375);
FORCEADD VCCAUX15..1
(-5925 10375);
FORCEPROP 3 LASTPIN (-5925 10325) SIG_NAME P3V3_AUX\g
J 0
(-5915 10335);
DISPLAY 0.659574 (-5915 10335);
PAINT MONO (-5915 10335);
DISPLAY INVISIBLE (-5915 10335);
FORCEPROP 1 LAST HDL_POWER P3V3_AUX
J 1
(-5925 10425);
DISPLAY 0.723404 (-5925 10425);
PAINT GREEN (-5925 10425);
FORCEPROP 2 LAST CDS_LIB pure_quanta_power
J 0
(-5925 10375);
DISPLAY INVISIBLE (-5925 10375);
FORCEPROP 1 LAST PATH I83
J 0
(-5875 10400);
DISPLAY 0.872340 (-5875 10400);
PAINT AQUA (-5875 10400);
DISPLAY INVISIBLE (-5875 10400);
FORCEADD Q_RES..1
(-3975 8400);
FORCEPROP 1 LAST LOCATION R3872
J 0
(-4025 8450);
DISPLAY 0.978723 (-4025 8450);
FORCEPROP 0 LAST $SEC 1
J 0
(-4025 8500);
DISPLAY 0.680851 (-4025 8500);
PAINT MONO (-4025 8500);
DISPLAY INVISIBLE (-4025 8500);
FORCEPROP 0 LAST CDS_SEC 1
J 0
(-4025 8500);
DISPLAY 1.021277 (-4025 8500);
DISPLAY INVISIBLE (-4025 8500);
FORCEPROP 1 LASTPIN (-4075 8400) $PN 1
J 0
(-4063 8412);
DISPLAY 0.787234 (-4063 8412);
PAINT MONO (-4063 8412);
FORCEPROP 1 LASTPIN (-3875 8400) $PN 2
J 0
(-3913 8412);
DISPLAY 0.787234 (-3913 8412);
PAINT MONO (-3913 8412);
FORCEPROP 0 LAST ROOM NIC_P12V_MPS_TIC_BOM3
J 0
(-4150 8275);
DISPLAY 0.680851 (-4150 8275);
PAINT RED (-4150 8275);
FORCEPROP 1 LAST TOLERANCE 5%
J 0
(-3800 8400);
DISPLAY 0.595745 (-3800 8400);
FORCEPROP 1 LAST PACK_TYPE 0402LF
J 0
(-3825 8350);
DISPLAY 0.595745 (-3825 8350);
FORCEPROP 1 LAST MATERIAL EMPTY
J 0
(-4200 8400);
DISPLAY 0.595745 (-4200 8400);
PAINT RED (-4200 8400);
FORCEPROP 1 LAST VALUE 0
J 2
(-3825 8400);
DISPLAY 0.595745 (-3825 8400);
FORCEPROP 1 LAST WATTAGE 1/16W
J 2
(-4175 8350);
DISPLAY 0.595745 (-4175 8350);
FORCEPROP 2 LAST CDS_LIB pure_quanta
J 0
(-3975 8400);
DISPLAY INVISIBLE (-3975 8400);
FORCEPROP 1 LAST PATH I84
J 0
(-4025 8550);
DISPLAY 0.978723 (-4025 8550);
PAINT WHITE (-4025 8550);
DISPLAY INVISIBLE (-4025 8550);
FORCEPROP 1 LAST PART_NUMBER CS00002JB13
J 0
(-4150 8350);
DISPLAY 0.595745 (-4150 8350);
DISPLAY INVISIBLE (-4150 8350);
FORCEADD Q_RES..1
(-3975 8575);
FORCEPROP 1 LAST LOCATION R3871
J 0
(-4025 8625);
DISPLAY 0.978723 (-4025 8625);
FORCEPROP 0 LAST $SEC 1
J 0
(-4025 8675);
DISPLAY 0.680851 (-4025 8675);
PAINT MONO (-4025 8675);
DISPLAY INVISIBLE (-4025 8675);
FORCEPROP 0 LAST CDS_SEC 1
J 0
(-4025 8675);
DISPLAY 1.021277 (-4025 8675);
DISPLAY INVISIBLE (-4025 8675);
FORCEPROP 1 LASTPIN (-4075 8575) $PN 1
J 0
(-4063 8587);
DISPLAY 0.787234 (-4063 8587);
PAINT MONO (-4063 8587);
FORCEPROP 1 LASTPIN (-3875 8575) $PN 2
J 0
(-3913 8587);
DISPLAY 0.787234 (-3913 8587);
PAINT MONO (-3913 8587);
FORCEPROP 1 LAST TOLERANCE 5%
J 0
(-3800 8575);
DISPLAY 0.595745 (-3800 8575);
FORCEPROP 1 LAST PACK_TYPE 0402LF
J 0
(-3825 8525);
DISPLAY 0.595745 (-3825 8525);
FORCEPROP 0 LAST ROOM NIC_P12V_MPS_MAM_BOM2
J 0
(-4125 8675);
DISPLAY 0.553191 (-4125 8675);
PAINT RED (-4125 8675);
FORCEPROP 1 LAST MATERIAL CHIP
J 0
(-4200 8575);
DISPLAY 0.595745 (-4200 8575);
PAINT RED (-4200 8575);
FORCEPROP 1 LAST WATTAGE 1/16W
J 2
(-4175 8525);
DISPLAY 0.595745 (-4175 8525);
FORCEPROP 1 LAST VALUE 0
J 2
(-3825 8575);
DISPLAY 0.595745 (-3825 8575);
FORCEPROP 2 LAST CDS_LIB pure_quanta
J 0
(-3975 8575);
DISPLAY INVISIBLE (-3975 8575);
FORCEPROP 1 LAST PATH I85
J 0
(-4025 8725);
DISPLAY 0.978723 (-4025 8725);
PAINT WHITE (-4025 8725);
DISPLAY INVISIBLE (-4025 8725);
FORCEPROP 1 LAST PART_NUMBER CS00002JB13
J 0
(-4150 8525);
DISPLAY 0.595745 (-4150 8525);
DISPLAY INVISIBLE (-4150 8525);
FORCEADD Q_CAP..1
(-3875 9075);
FORCEPROP 1 LAST LOCATION PC2158
J 0
(-3800 9175);
DISPLAY 0.638298 (-3800 9175);
FORCEPROP 0 LAST $SEC 1
J 0
(-3800 9225);
DISPLAY INVISIBLE (-3800 9225);
FORCEPROP 0 LAST CDS_SEC 1
J 0
(-3800 9225);
DISPLAY INVISIBLE (-3800 9225);
FORCEPROP 1 LASTPIN (-3875 9175) $PN 1
J 0
(-3865 9155);
DISPLAY 0.787234 (-3865 9155);
PAINT MONO (-3865 9155);
DISPLAY INVISIBLE (-3865 9155);
FORCEPROP 1 LASTPIN (-3875 8975) $PN 2
J 0
(-3865 8955);
DISPLAY 0.787234 (-3865 8955);
PAINT MONO (-3865 8955);
DISPLAY INVISIBLE (-3865 8955);
FORCEPROP 0 LAST ROOM NIC_P12V_MPS_MAM_BOM2
J 0
(-3825 8825);
DISPLAY 0.446809 (-3825 8825);
PAINT RED (-3825 8825);
FORCEPROP 1 LAST MATERIAL X7R
J 0
(-3825 8975);
DISPLAY 0.638298 (-3825 8975);
PAINT RED (-3825 8975);
FORCEPROP 1 LAST TOLERANCE 20%
J 0
(-3825 9025);
DISPLAY 0.638298 (-3825 9025);
FORCEPROP 1 LAST VOLTAGE 16V
J 0
(-3825 9075);
DISPLAY 0.638298 (-3825 9075);
FORCEPROP 1 LAST VALUE 2.2UF
J 0
(-3825 9125);
DISPLAY 0.638298 (-3825 9125);
FORCEPROP 1 LAST PACK_TYPE C0603
J 0
(-3825 8875);
DISPLAY 0.638298 (-3825 8875);
FORCEPROP 2 LAST CDS_LIB pure_quanta
J 0
(-3875 9075);
DISPLAY INVISIBLE (-3875 9075);
FORCEPROP 1 LAST PATH I86
J 0
(-3825 9225);
DISPLAY 0.978723 (-3825 9225);
PAINT WHITE (-3825 9225);
DISPLAY INVISIBLE (-3825 9225);
FORCEPROP 1 LAST PART_NUMBER CH5223M1900
J 0
(-3825 8925);
DISPLAY 0.638298 (-3825 8925);
DISPLAY INVISIBLE (-3825 8925);
FORCEADD OFFPAGE..2
(-3225 9225);
PAINT AQUA (-3225 9225);
FORCEPROP 2 LAST $XR0 135 
J 0
(-3036 9225);
DISPLAY 0.638298 (-3036 9225);
PAINT MONO (-3036 9225);
FORCEPROP 2 LAST CDS_LIB standard
J 0
(-3225 9225);
DISPLAY INVISIBLE (-3225 9225);
FORCEPROP 1 LAST OFFPAGE TRUE
J 0
(-2900 9100);
DISPLAY 0.872340 (-2900 9100);
PAINT AQUA (-2900 9100);
DISPLAY INVISIBLE (-2900 9100);
FORCEPROP 1 LAST COMMENT_BODY TRUE
J 0
(-3270 9130);
DISPLAY 0.872340 (-3270 9130);
PAINT GREEN (-3270 9130);
DISPLAY INVISIBLE (-3270 9130);
FORCEPROP 2 LAST PATH I87
J 0
(-3025 9275);
DISPLAY 0.680851 (-3025 9275);
DISPLAY INVISIBLE (-3025 9275);
FORCEADD Q_RES..2
(-3875 9500);
FORCEPROP 1 LAST LOCATION PR3843
J 0
(-3830 9625);
DISPLAY 0.638298 (-3830 9625);
FORCEPROP 0 LAST $SEC 1
J 0
(-3825 9675);
DISPLAY 0.680851 (-3825 9675);
PAINT MONO (-3825 9675);
DISPLAY INVISIBLE (-3825 9675);
FORCEPROP 0 LAST CDS_SEC 1
J 0
(-3825 9675);
DISPLAY 1.021277 (-3825 9675);
DISPLAY INVISIBLE (-3825 9675);
FORCEPROP 1 LASTPIN (-3875 9600) $PN 1
J 0
(-3870 9562);
DISPLAY 0.787234 (-3870 9562);
PAINT MONO (-3870 9562);
FORCEPROP 1 LASTPIN (-3875 9400) $PN 2
J 0
(-3870 9410);
DISPLAY 0.787234 (-3870 9410);
PAINT MONO (-3870 9410);
FORCEPROP 1 LAST TOLERANCE 1%
J 0
(-3830 9525);
DISPLAY 0.638298 (-3830 9525);
FORCEPROP 1 LAST VALUE 49.9
J 0
(-3830 9575);
DISPLAY 0.638298 (-3830 9575);
FORCEPROP 1 LAST PACK_TYPE 0603LF
J 0
(-3835 9325);
DISPLAY 0.638298 (-3835 9325);
FORCEPROP 1 LAST MATERIAL CHIP
J 0
(-3835 9425);
DISPLAY 0.638298 (-3835 9425);
PAINT RED (-3835 9425);
FORCEPROP 1 LAST WATTAGE 1/10W
J 0
(-3835 9475);
DISPLAY 0.638298 (-3835 9475);
FORCEPROP 0 LAST ROOM NIC_P12V_MPS_MAM_BOM2
J 0
(-3825 9675);
DISPLAY 0.446809 (-3825 9675);
PAINT RED (-3825 9675);
FORCEPROP 2 LAST CDS_LIB pure_quanta
J 0
(-3875 9500);
DISPLAY INVISIBLE (-3875 9500);
FORCEPROP 1 LAST PATH I88
J 0
(-3825 9675);
DISPLAY 0.978723 (-3825 9675);
PAINT WHITE (-3825 9675);
DISPLAY INVISIBLE (-3825 9675);
FORCEPROP 1 LAST PART_NUMBER CS04993F909
J 0
(-3835 9375);
DISPLAY 0.638298 (-3835 9375);
DISPLAY INVISIBLE (-3835 9375);
FORCEADD UNIVERSAL_POWER..1
(-3875 9800);
FORCEPROP 3 LASTPIN (-3875 9750) SIG_NAME P12V_AUX\g
J 0
(-3865 9760);
DISPLAY 0.659574 (-3865 9760);
PAINT MONO (-3865 9760);
DISPLAY INVISIBLE (-3865 9760);
FORCEPROP 1 LAST HDL_POWER P12V_AUX
J 1
(-3875 9850);
DISPLAY 0.702128 (-3875 9850);
PAINT GREEN (-3875 9850);
FORCEPROP 2 LAST CDS_LIB pure_quanta_power
J 0
(-3875 9800);
DISPLAY INVISIBLE (-3875 9800);
FORCEPROP 1 LAST PATH I89
J 0
(-3825 9825);
DISPLAY 0.872340 (-3825 9825);
PAINT AQUA (-3825 9825);
DISPLAY INVISIBLE (-3825 9825);
FORCEADD GND..1
(-3525 9750);
FORCEPROP 3 LASTPIN (-3525 9800) SIG_NAME GND\g
J 0
(-3515 9810);
DISPLAY 0.659574 (-3515 9810);
PAINT MONO (-3515 9810);
DISPLAY INVISIBLE (-3515 9810);
FORCEPROP 1 LAST SIZE 1B
J 0
(-3450 9700);
DISPLAY 0.872340 (-3450 9700);
PAINT GREEN (-3450 9700);
DISPLAY INVISIBLE (-3450 9700);
FORCEPROP 2 LAST CDS_LIB pure_quanta_power
J 0
(-3525 9750);
DISPLAY INVISIBLE (-3525 9750);
FORCEPROP 1 LAST HDL_POWER GND
J 0
(-3525 9900);
DISPLAY 0.872340 (-3525 9900);
PAINT GREEN (-3525 9900);
DISPLAY INVISIBLE (-3525 9900);
FORCEPROP 1 LAST PATH I90
J 0
(-3450 9750);
DISPLAY 0.872340 (-3450 9750);
PAINT AQUA (-3450 9750);
DISPLAY INVISIBLE (-3450 9750);
FORCEADD Q_CAP..1
R 2
(-3525 9925);
FORCEPROP 1 LAST LOCATION PC2160
J 0
(-3450 10075);
DISPLAY 0.638298 (-3450 10075);
FORCEPROP 0 LAST $SEC 1
J 0
(-3175 10075);
DISPLAY 0.680851 (-3175 10075);
PAINT MONO (-3175 10075);
DISPLAY INVISIBLE (-3175 10075);
FORCEPROP 0 LAST CDS_SEC 1
J 0
(-3175 10075);
DISPLAY 1.021277 (-3175 10075);
DISPLAY INVISIBLE (-3175 10075);
FORCEPROP 1 LASTPIN (-3525 10025) $PN 1
J 2
(-3535 10005);
DISPLAY 0.787234 (-3535 10005);
PAINT MONO (-3535 10005);
FORCEPROP 1 LASTPIN (-3525 9825) $PN 2
J 2
(-3535 9805);
DISPLAY 0.787234 (-3535 9805);
PAINT MONO (-3535 9805);
FORCEPROP 1 LAST VOLTAGE 25V
J 0
(-3450 10000);
DISPLAY 0.510638 (-3450 10000);
FORCEPROP 0 LAST ROOM NIC_P12V_MPS_MAM_BOM2
J 0
(-3450 10175);
DISPLAY 0.680851 (-3450 10175);
PAINT RED (-3450 10175);
FORCEPROP 1 LAST VALUE 0.1UF
J 0
(-3450 10050);
DISPLAY 0.510638 (-3450 10050);
FORCEPROP 1 LAST TOLERANCE 10%
J 0
(-3450 9950);
DISPLAY 0.510638 (-3450 9950);
FORCEPROP 1 LAST MATERIAL X7R
J 0
(-3450 9900);
DISPLAY 0.510638 (-3450 9900);
PAINT RED (-3450 9900);
FORCEPROP 1 LAST PACK_TYPE 0402
J 0
(-3450 9800);
DISPLAY 0.510638 (-3450 9800);
FORCEPROP 2 LAST CDS_LIB pure_quanta
J 0
(-3525 9925);
DISPLAY INVISIBLE (-3525 9925);
FORCEPROP 1 LAST PATH I91
J 2
(-3575 10075);
DISPLAY 0.978723 (-3575 10075);
PAINT WHITE (-3575 10075);
DISPLAY INVISIBLE (-3575 10075);
FORCEPROP 1 LAST PART_NUMBER CH4104K1B00
J 0
(-3450 9850);
DISPLAY 0.510638 (-3450 9850);
DISPLAY INVISIBLE (-3450 9850);
FORCEADD UNIVERSAL_POWER..1
R 2
(-3525 10200);
FORCEPROP 3 LASTPIN (-3525 10150) SIG_NAME P12V_OCP_SFF\g
J 0
(-3515 10160);
DISPLAY 0.659574 (-3515 10160);
PAINT MONO (-3515 10160);
DISPLAY INVISIBLE (-3515 10160);
FORCEPROP 1 LAST HDL_POWER P12V_OCP_SFF
J 1
(-3525 10250);
DISPLAY 0.723404 (-3525 10250);
PAINT GREEN (-3525 10250);
FORCEPROP 2 LAST CDS_LIB pure_quanta_power
J 0
(-3525 10200);
DISPLAY INVISIBLE (-3525 10200);
FORCEPROP 1 LAST PATH I92
J 2
(-3575 10225);
DISPLAY 0.872340 (-3575 10225);
PAINT AQUA (-3575 10225);
DISPLAY INVISIBLE (-3575 10225);
FORCEADD OFFPAGE..2
(-2725 8575);
PAINT AQUA (-2725 8575);
FORCEPROP 2 LAST $XR0 258 
J 0
(-2536 8575);
DISPLAY 0.638298 (-2536 8575);
PAINT MONO (-2536 8575);
FORCEPROP 2 LAST CDS_LIB standard
J 0
(-2725 8575);
DISPLAY INVISIBLE (-2725 8575);
FORCEPROP 1 LAST OFFPAGE TRUE
J 0
(-2400 8450);
DISPLAY 0.872340 (-2400 8450);
PAINT AQUA (-2400 8450);
DISPLAY INVISIBLE (-2400 8450);
FORCEPROP 1 LAST COMMENT_BODY TRUE
J 0
(-2770 8480);
DISPLAY 0.872340 (-2770 8480);
PAINT GREEN (-2770 8480);
DISPLAY INVISIBLE (-2770 8480);
FORCEPROP 2 LAST PATH I93
J 0
(-2525 8625);
DISPLAY 0.680851 (-2525 8625);
DISPLAY INVISIBLE (-2525 8625);
FORCEADD OFFPAGE..2
(-2725 8400);
PAINT AQUA (-2725 8400);
FORCEPROP 2 LAST $XR0 258 
J 0
(-2536 8400);
DISPLAY 0.638298 (-2536 8400);
PAINT MONO (-2536 8400);
FORCEPROP 2 LAST CDS_LIB standard
J 0
(-2725 8400);
DISPLAY INVISIBLE (-2725 8400);
FORCEPROP 1 LAST OFFPAGE TRUE
J 0
(-2400 8275);
DISPLAY 0.872340 (-2400 8275);
PAINT AQUA (-2400 8275);
DISPLAY INVISIBLE (-2400 8275);
FORCEPROP 1 LAST COMMENT_BODY TRUE
J 0
(-2770 8305);
DISPLAY 0.872340 (-2770 8305);
PAINT GREEN (-2770 8305);
DISPLAY INVISIBLE (-2770 8305);
FORCEPROP 2 LAST PATH I94
J 0
(-2525 8450);
DISPLAY 0.680851 (-2525 8450);
DISPLAY INVISIBLE (-2525 8450);
FORCEADD VCCAUX15..1
(-4775 9150);
FORCEPROP 3 LASTPIN (-4775 9100) SIG_NAME P3V3_AUX\g
J 0
(-4765 9110);
DISPLAY 0.659574 (-4765 9110);
PAINT MONO (-4765 9110);
DISPLAY INVISIBLE (-4765 9110);
FORCEPROP 1 LAST HDL_POWER P3V3_AUX
J 1
(-4775 9175);
DISPLAY 0.574468 (-4775 9175);
PAINT GREEN (-4775 9175);
FORCEPROP 2 LAST CDS_LIB pure_quanta_power
J 0
(-4775 9150);
DISPLAY INVISIBLE (-4775 9150);
FORCEPROP 1 LAST PATH I95
J 0
(-4725 9175);
DISPLAY 0.872340 (-4725 9175);
PAINT AQUA (-4725 9175);
DISPLAY INVISIBLE (-4725 9175);
FORCEADD UNIVERSAL_GND..1
(-4450 11900);
FORCEPROP 3 LASTPIN (-4450 11950) SIG_NAME GND\g
J 0
(-4440 11960);
DISPLAY 0.659574 (-4440 11960);
PAINT MONO (-4440 11960);
DISPLAY INVISIBLE (-4440 11960);
FORCEPROP 2 LAST CDS_LIB pure_quanta_power
J 0
(-4450 11900);
DISPLAY INVISIBLE (-4450 11900);
FORCEPROP 1 LAST HDL_POWER GND
J 1
(-4425 11825);
DISPLAY 0.872340 (-4425 11825);
PAINT GREEN (-4425 11825);
DISPLAY INVISIBLE (-4425 11825);
FORCEPROP 1 LAST PATH I97
J 0
(-4375 11900);
DISPLAY 0.872340 (-4375 11900);
PAINT AQUA (-4375 11900);
DISPLAY INVISIBLE (-4375 11900);
FORCEADD Q_CAP..1
(-4450 12275);
FORCEPROP 1 LAST LOCATION PC2157
J 0
(-4400 12350);
DISPLAY 0.723404 (-4400 12350);
PAINT AQUA (-4400 12350);
FORCEPROP 0 LAST $SEC 1
J 0
(-4400 12400);
DISPLAY INVISIBLE (-4400 12400);
FORCEPROP 0 LAST CDS_SEC 1
J 0
(-4400 12400);
DISPLAY INVISIBLE (-4400 12400);
FORCEPROP 1 LASTPIN (-4450 12375) $PN 1
J 0
(-4440 12355);
DISPLAY 0.787234 (-4440 12355);
PAINT MONO (-4440 12355);
DISPLAY INVISIBLE (-4440 12355);
FORCEPROP 1 LASTPIN (-4450 12175) $PN 2
J 0
(-4440 12155);
DISPLAY 0.787234 (-4440 12155);
PAINT MONO (-4440 12155);
DISPLAY INVISIBLE (-4440 12155);
FORCEPROP 1 LAST PACK_TYPE 0402
J 0
(-4400 12175);
DISPLAY 0.574468 (-4400 12175);
PAINT SKYBLUE (-4400 12175);
FORCEPROP 1 LAST MATERIAL NPO
J 0
(-4400 12250);
DISPLAY 0.574468 (-4400 12250);
PAINT RED (-4400 12250);
FORCEPROP 0 LAST ROOM NIC_P3V3_BOM2
J 0
(-4400 12075);
DISPLAY 0.553191 (-4400 12075);
PAINT RED (-4400 12075);
FORCEPROP 1 LAST VALUE 39PF
J 0
(-4400 12300);
DISPLAY 0.574468 (-4400 12300);
PAINT SKYBLUE (-4400 12300);
FORCEPROP 1 LAST VOLTAGE 50V
J 0
(-4400 12225);
DISPLAY 0.574468 (-4400 12225);
PAINT SKYBLUE (-4400 12225);
FORCEPROP 2 LAST CDS_LIB pure_quanta
J 0
(-4450 12275);
DISPLAY INVISIBLE (-4450 12275);
FORCEPROP 1 LAST TOLERANCE 5%
J 0
(-4400 12225);
DISPLAY 0.723404 (-4400 12225);
PAINT SKYBLUE (-4400 12225);
DISPLAY INVISIBLE (-4400 12225);
FORCEPROP 1 LAST PATH I98
J 0
(-4400 12425);
DISPLAY 0.978723 (-4400 12425);
PAINT WHITE (-4400 12425);
DISPLAY INVISIBLE (-4400 12425);
FORCEPROP 1 LAST PART_NUMBER CH03906JB06
J 0
(-4400 12125);
DISPLAY 0.574468 (-4400 12125);
PAINT WHITE (-4400 12125);
DISPLAY INVISIBLE (-4400 12125);
FORCEADD OFFPAGE..1
(-4775 12575);
PAINT AQUA (-4775 12575);
FORCEPROP 2 LAST $XR0 80 
J 0
(-4996 12575);
DISPLAY 0.638298 (-4996 12575);
PAINT MONO (-4996 12575);
FORCEPROP 2 LAST $XR1 83 
J 0
(-5086 12575);
DISPLAY 0.638298 (-5086 12575);
PAINT MONO (-5086 12575);
FORCEPROP 2 LAST $XR2 134 
J 0
(-5206 12575);
DISPLAY 0.638298 (-5206 12575);
PAINT MONO (-5206 12575);
FORCEPROP 2 LAST $XR3 248 
J 0
(-5326 12575);
DISPLAY 0.638298 (-5326 12575);
PAINT MONO (-5326 12575);
FORCEPROP 2 LAST CDS_LIB standard
J 0
(-4775 12575);
DISPLAY INVISIBLE (-4775 12575);
FORCEPROP 1 LAST OFFPAGE TRUE
J 0
(-4450 12450);
DISPLAY 0.872340 (-4450 12450);
PAINT AQUA (-4450 12450);
DISPLAY INVISIBLE (-4450 12450);
FORCEPROP 1 LAST COMMENT_BODY TRUE
J 0
(-4650 12475);
DISPLAY 0.872340 (-4650 12475);
PAINT GREEN (-4650 12475);
DISPLAY INVISIBLE (-4650 12475);
FORCEPROP 2 LAST PATH I99
J 0
(-5025 12625);
DISPLAY 0.680851 (-5025 12625);
DISPLAY INVISIBLE (-5025 12625);
FORCEADD DNS..2
(-3950 8425);
PAINT RED (-3950 8425);
FORCEPROP 2 LAST CDS_LIB mstr_misc
J 0
(-3950 8425);
DISPLAY INVISIBLE (-3950 8425);
FORCEPROP 1 LAST COMMENT_BODY TRUE
R 1
J 0
(-3875 8200);
DISPLAY 0.872340 (-3875 8200);
PAINT GREEN (-3875 8200);
DISPLAY INVISIBLE (-3875 8200);
FORCEADD DNS..2
(-5375 9575);
PAINT RED (-5375 9575);
FORCEPROP 2 LAST CDS_LIB mstr_misc
J 0
(-5375 9575);
DISPLAY INVISIBLE (-5375 9575);
FORCEPROP 1 LAST COMMENT_BODY TRUE
R 1
J 0
(-5300 9350);
DISPLAY 0.872340 (-5300 9350);
PAINT GREEN (-5300 9350);
DISPLAY INVISIBLE (-5300 9350);
FORCEADD DNS..2
(-7725 9625);
PAINT RED (-7725 9625);
FORCEPROP 2 LAST CDS_LIB mstr_misc
J 0
(-7725 9625);
DISPLAY INVISIBLE (-7725 9625);
FORCEPROP 1 LAST COMMENT_BODY TRUE
R 1
J 0
(-7650 9400);
DISPLAY 0.872340 (-7650 9400);
PAINT GREEN (-7650 9400);
DISPLAY INVISIBLE (-7650 9400);
FORCEADD DNS..2
(-4775 9575);
PAINT RED (-4775 9575);
FORCEPROP 2 LAST CDS_LIB mstr_misc
J 0
(-4775 9575);
DISPLAY INVISIBLE (-4775 9575);
FORCEPROP 1 LAST COMMENT_BODY TRUE
R 1
J 0
(-4700 9350);
DISPLAY 0.872340 (-4700 9350);
PAINT GREEN (-4700 9350);
DISPLAY INVISIBLE (-4700 9350);
FORCEADD CAD_NOTE..1
(-3050 8275);
FORCEPROP 0 LAST S1 R3871/R3872 CO-LAYOUT
J 0
(-3175 8150);
DISPLAY 0.808511 (-3175 8150);
PAINT WHITE (-3175 8150);
FORCEPROP 2 LAST CDS_LIB pure_quanta_power
J 0
(-3050 8275);
DISPLAY INVISIBLE (-3050 8275);
FORCEPROP 1 LAST COMMENT_BODY TRUE
J 0
(-3025 8375);
DISPLAY 0.978723 (-3025 8375);
DISPLAY INVISIBLE (-3025 8375);
FORCEADD DNS..2
(-3975 12925);
PAINT RED (-3975 12925);
FORCEPROP 2 LAST CDS_LIB mstr_misc
J 0
(-3975 12925);
DISPLAY INVISIBLE (-3975 12925);
FORCEPROP 1 LAST COMMENT_BODY TRUE
R 1
J 0
(-3900 12700);
DISPLAY 0.872340 (-3900 12700);
PAINT GREEN (-3900 12700);
DISPLAY INVISIBLE (-3900 12700);
FORCEADD QUANTA_TITLE_BLOCK_C..1
(-200 7750);
FORCEPROP 0 LAST CDS_CON_LAST_MODIFIED Thu Sep 14 16:12:39 2023
J 0
(-2085 7765);
DISPLAY INVISIBLE (-2085 7765);
FORCEPROP 2 LAST CUSTOM_TXT_CDS <XR_PAGE_TITLE>
J 0
(-8090 13000);
DISPLAY 0.638298 (-8090 13000);
PAINT PINK (-8090 13000);
DISPLAY INVISIBLE (-8090 13000);
FORCEPROP 2 LAST CUSTOM_TXT_CDS <CON_LAST_MODIFIED>
J 0
(-2085 7765);
DISPLAY 0.978723 (-2085 7765);
FORCEPROP 2 LAST CUSTOM_TXT_CDS <Q_REV>
J 0
(-384 7853);
DISPLAY 1.212766 (-384 7853);
FORCEPROP 2 LAST CUSTOM_TXT_CDS <CON_PAGE_NUM> OF <CON_TOTAL_PAGES>
J 0
(-646 7768);
DISPLAY 0.978723 (-646 7768);
FORCEPROP 2 LAST CUSTOM_TXT_CDS <Q_PROJ>
J 0
(-2582 7852);
DISPLAY 1.212766 (-2582 7852);
FORCEPROP 2 LAST CUSTOM_TXT_CDS <Q_NUMBER>
J 0
(-1603 7853);
DISPLAY 1.212766 (-1603 7853);
FORCEPROP 2 LAST CUSTOM_TXT_CDS <NAME_2>
J 0
(-3375 7800);
FORCEPROP 2 LAST CUSTOM_TXT_CDS <NAME_1>
J 0
(-3375 7925);
FORCEPROP 1 LAST Q_TITLE SFF_OCP3.0 HSC CO-LAYOUT(2/3)
J 0
(-9516 7801);
DISPLAY 2.446809 (-9516 7801);
PAINT GREEN (-9516 7801);
FORCEPROP 2 LAST CDS_XR_PAGE_TITLE CR-135 : @T6G_MB_LIB.T6G(SCH_1):PAGE135
J 0
(-8090 13000);
DISPLAY 0.638298 (-8090 13000);
PAINT PINK (-8090 13000);
DISPLAY INVISIBLE (-8090 13000);
FORCEPROP 2 LAST PAGE_BORDER TRUE
J 0
(-8090 13000);
DISPLAY 0.638298 (-8090 13000);
PAINT PINK (-8090 13000);
DISPLAY INVISIBLE (-8090 13000);
FORCEPROP 1 LAST CDS_LMAN_SYM_OUTLINE -9475,6775,100,-125
J 0
(-200 7750);
DISPLAY 0.468085 (-200 7750);
PAINT GREEN (-200 7750);
DISPLAY INVISIBLE (-200 7750);
FORCEPROP 2 LAST CDS_LIB pure_quanta
J 0
(-200 7750);
DISPLAY INVISIBLE (-200 7750);
FORCEPROP 1 LAST Q_DEPT BU9
J 1
(-3963 7799);
DISPLAY 1.957447 (-3963 7799);
PAINT GREEN (-3963 7799);
DISPLAY INVISIBLE (-3963 7799);
FORCEPROP 1 LAST COMMENT_BODY TRUE
J 0
(-188 7737);
DISPLAY 0.978723 (-188 7737);
PAINT GREEN (-188 7737);
DISPLAY INVISIBLE (-188 7737);
FORCEADD DNS..2
(-3900 12600);
PAINT RED (-3900 12600);
FORCEPROP 2 LAST CDS_LIB mstr_misc
J 0
(-3900 12600);
DISPLAY INVISIBLE (-3900 12600);
FORCEPROP 1 LAST COMMENT_BODY TRUE
R 1
J 0
(-3825 12375);
DISPLAY 0.872340 (-3825 12375);
PAINT GREEN (-3825 12375);
DISPLAY INVISIBLE (-3825 12375);
WIRE 16 -1 (-3600 12125)(-3600 11950);
WIRE 16 -1 (-3050 12100)(-3050 11950);
WIRE 16 -1 (-950 12050)(-950 12250);
WIRE 16 -1 (-3400 12750)(-3400 12700);
WIRE 16 -1 (-950 12675)(-950 12950);
WIRE 16 -1 (-950 12675)(-950 12450);
WIRE 16 -1 (-2000 12675)(-950 12675);
WIRE 16 -1 (-8025 8850)(-8025 9050);
WIRE 16 -1 (-7600 8775)(-7600 8925);
WIRE 16 -1 (-7200 8750)(-7200 8825);
WIRE 16 -1 (-7275 9825)(-7275 9900);
WIRE 16 -1 (-5925 10325)(-5925 10275);
WIRE 16 -1 (-3525 9800)(-3525 9825);
WIRE 16 -1 (-5300 9100)(-4775 9100);
WIRE 16 2175 (-9350 13900)(-7647 13900);
WIRE 16 2175 (-9350 13900)(-9350 13000);
WIRE 16 2175 (-7647 13900)(-7647 13000);
WIRE 16 2175 (-9350 13000)(-7647 13000);
WIRE 16 -1 (-6000 9450)(-5693 9450);
WIRE 16 -1 (-5693 9500)(-5693 9450);
WIRE 16 -1 (-5693 9500)(-5693 9550);
WIRE 16 -1 (-6000 9500)(-5693 9500);
WIRE 16 -1 (-5693 9550)(-5693 9600);
WIRE 16 -1 (-6000 9550)(-5693 9550);
WIRE 16 -1 (-5693 9600)(-5693 9650);
WIRE 16 -1 (-5693 9600)(-6000 9600);
WIRE 16 -1 (-5693 9650)(-5693 9700);
WIRE 16 -1 (-6000 9650)(-5693 9650);
WIRE 16 -1 (-5693 9700)(-5693 9750);
WIRE 16 -1 (-6000 9700)(-5693 9700);
WIRE 16 -1 (-5693 9750)(-5693 9800);
WIRE 16 -1 (-6000 9750)(-5693 9750);
WIRE 16 -1 (-5693 9800)(-5400 9800);
WIRE 16 -1 (-6000 9800)(-5693 9800);
WIRE 16 -1 (-5400 9800)(-4800 9800);
WIRE 16 -1 (-5400 9675)(-5400 9800);
WIRE 16 -1 (-4800 9800)(-4800 10100);
WIRE 16 -1 (-4800 9800)(-4800 9675);
WIRE 16 -1 (-4800 10100)(-3525 10100);
WIRE 16 -1 (-3525 10100)(-3525 10150);
WIRE 16 -1 (-3525 10025)(-3525 10100);
WIRE 16 -1 (-6800 9750)(-6880 9750);
WIRE 16 -1 (-6880 9750)(-6880 9800);
WIRE 16 -1 (-6800 9800)(-6880 9800);
WIRE 16 -1 (-6880 9800)(-6880 9850);
WIRE 16 -1 (-6880 9850)(-6880 9900);
WIRE 16 -1 (-6800 9850)(-6880 9850);
WIRE 16 -1 (-6800 9900)(-6880 9900);
WIRE 16 -1 (-6880 9900)(-6880 9950);
WIRE 16 -1 (-6880 10200)(-6880 9950);
WIRE 16 -1 (-6880 9950)(-6800 9950);
WIRE 16 -1 (-6880 10200)(-7275 10200);
WIRE 16 -1 (-7275 10300)(-7275 10200);
WIRE 16 -1 (-7275 10200)(-7275 10100);
WIRE 16 -1 (-5400 9475)(-5400 9350);
WIRE 16 -1 (-5400 9350)(-5250 9350);
WIRE 16 -1 (-6000 9350)(-5400 9350);
FORCEPROP 2 LAST SIG_NAME P12V_OCP_AVIN_PD_1
J 0
(-5910 9360);
DISPLAY 0.574468 (-5910 9360);
WIRE 16 -1 (-4400 9400)(-4400 9250);
WIRE 16 -1 (-4400 9250)(-4800 9250);
WIRE 16 -1 (-4400 9250)(-4400 9175);
WIRE 16 -1 (-4800 9475)(-4800 9250);
WIRE 16 -1 (-6000 9250)(-4800 9250);
FORCEPROP 2 LAST SIG_NAME P12V_OCP_OV_FB_1
J 0
(-5910 9260);
DISPLAY 0.574468 (-5910 9260);
FORCEPROP 2 LASTPROP $XRERR UNIQUE?
J 0
(-6150 9260);
DISPLAY 0.638298 (-6150 9260);
PAINT MONO (-6150 9260);
DISPLAY INVISIBLE (-6150 9260);
WIRE 16 -1 (-5925 10075)(-5925 9950);
WIRE 16 -1 (-5175 9950)(-5925 9950);
FORCEPROP 2 LAST SIG_NAME HP_LVC3_OCP_V3_1_P12V_PWRGD
J 0
(-5885 9960);
DISPLAY 0.574468 (-5885 9960);
WIRE 16 -1 (-6000 9950)(-5925 9950);
WIRE 16 -1 (-5500 9100)(-6000 9100);
FORCEPROP 2 LAST SIG_NAME P12V_OCP_FLTB_1
J 0
(-5910 9110);
DISPLAY 0.574468 (-5910 9110);
FORCEPROP 2 LASTPROP $XRERR UNIQUE?
J 0
(-6150 9110);
DISPLAY 0.638298 (-6150 9110);
PAINT MONO (-6150 9110);
DISPLAY INVISIBLE (-6150 9110);
WIRE 16 -1 (-4425 8400)(-4075 8400);
WIRE 16 -1 (-4425 8575)(-4425 8400);
WIRE 16 -1 (-4075 8575)(-4425 8575);
WIRE 16 -1 (-4700 8575)(-4425 8575);
WIRE 16 -1 (-4700 9000)(-4700 8575);
WIRE 16 -1 (-5325 9000)(-4700 9000);
WIRE 16 -1 (-5325 8825)(-5325 9000);
WIRE 16 -1 (-5775 9000)(-5325 9000);
WIRE 16 -1 (-5775 8825)(-5775 9000);
FORCEPROP 2 LAST SIG_NAME P12V_OCP_IMON_1
J 0
(-5910 9010);
DISPLAY 0.574468 (-5910 9010);
FORCEPROP 2 LASTPROP $XRERR UNIQUE?
J 0
(-6150 9010);
DISPLAY 0.638298 (-6150 9010);
PAINT MONO (-6150 9010);
DISPLAY INVISIBLE (-6150 9010);
WIRE 16 -1 (-6000 9000)(-5775 9000);
WIRE 16 -1 (-7725 9975)(-7425 9975);
WIRE 16 -1 (-7425 9975)(-7425 9600);
WIRE 16 -1 (-7425 9600)(-6800 9600);
FORCEPROP 2 LAST SIG_NAME P12V_OCP_EN_1_R2
J 0
(-7310 9610);
DISPLAY 0.574468 (-7310 9610);
FORCEPROP 2 LASTPROP $XRERR UNIQUE?
J 0
(-7550 9610);
DISPLAY 0.638298 (-7550 9610);
PAINT MONO (-7550 9610);
DISPLAY INVISIBLE (-7550 9610);
WIRE 16 -1 (-7625 9600)(-7425 9600);
WIRE 16 -1 (-6800 9500)(-7125 9500);
WIRE 16 -1 (-7125 9500)(-7125 9400);
WIRE 16 -1 (-7125 9400)(-6800 9400);
WIRE 16 -1 (-7125 9400)(-7600 9400);
WIRE 16 -1 (-6800 9300)(-8025 9300);
FORCEPROP 2 LAST SIG_NAME P12V_OCP_TIMER_1
J 0
(-7285 9310);
DISPLAY 0.574468 (-7285 9310);
FORCEPROP 2 LASTPROP $XRERR UNIQUE?
J 0
(-7525 9310);
DISPLAY 0.638298 (-7525 9310);
PAINT MONO (-7525 9310);
DISPLAY INVISIBLE (-7525 9310);
WIRE 16 -1 (-8025 9300)(-8025 9250);
WIRE 16 -1 (-6800 9200)(-7600 9200);
FORCEPROP 2 LAST SIG_NAME P12V_OCP_ISET_1
J 0
(-7260 9210);
DISPLAY 0.574468 (-7260 9210);
FORCEPROP 2 LASTPROP $XRERR UNIQUE?
J 0
(-7500 9210);
DISPLAY 0.638298 (-7500 9210);
PAINT MONO (-7500 9210);
DISPLAY INVISIBLE (-7500 9210);
WIRE 16 -1 (-7600 9200)(-7600 9125);
WIRE 16 -1 (-6800 9100)(-7200 9100);
FORCEPROP 2 LAST SIG_NAME P12V_OCP_SS_1
J 0
(-7210 9110);
DISPLAY 0.574468 (-7210 9110);
FORCEPROP 2 LASTPROP $XRERR UNIQUE?
J 0
(-7450 9110);
DISPLAY 0.638298 (-7450 9110);
PAINT MONO (-7450 9110);
DISPLAY INVISIBLE (-7450 9110);
WIRE 16 -1 (-7200 9100)(-7200 9025);
WIRE 16 -1 (-6859 9000)(-6800 9000);
WIRE 16 -1 (-6859 8916)(-6859 9000);
WIRE 16 -1 (-2000 12375)(-1825 12375);
WIRE 16 -1 (-1825 12375)(-1825 11950);
WIRE 16 -1 (-1825 11950)(-1550 11950);
WIRE 16 -1 (-1550 12025)(-1550 11950);
WIRE 16 -1 (-1550 11950)(-1550 11825);
WIRE 16 -1 (-3400 12950)(-3400 13050);
WIRE 16 -1 (-3400 13050)(-3325 13050);
WIRE 16 -1 (-3325 13050)(-3025 13050);
WIRE 16 -1 (-3325 13050)(-3325 13175);
WIRE 16 -1 (-3025 13050)(-3025 12675);
WIRE 16 -1 (-3025 12675)(-2800 12675);
WIRE 16 -1 (-5775 8625)(-5775 8445);
WIRE 16 -1 (-5775 8445)(-5325 8445);
WIRE 16 -1 (-5325 8445)(-5325 8625);
WIRE 16 -1 (-5325 8445)(-5325 8375);
WIRE 16 -1 (-4400 8975)(-4400 8825);
WIRE 16 -1 (-4400 8825)(-4200 8825);
WIRE 16 -1 (-4200 8825)(-3875 8825);
WIRE 16 -1 (-4200 8825)(-4200 8800);
WIRE 16 -1 (-3875 8825)(-3875 8975);
WIRE 16 -1 (-4400 9600)(-4400 9700);
WIRE 16 -1 (-4400 9700)(-3875 9700);
WIRE 16 -1 (-3875 9750)(-3875 9700);
WIRE 16 -1 (-3875 9700)(-3875 9600);
WIRE 16 -1 (-4025 12175)(-4025 12050);
WIRE 16 -1 (-4025 12050)(-4450 12050);
WIRE 16 -1 (-4450 12175)(-4450 12050);
WIRE 16 -1 (-4450 12050)(-4450 11950);
WIRE 16 -1 (-3875 8400)(-2775 8400);
FORCEPROP 2 LAST SIG_NAME P12V_OCP_SFF_ISENSE_MPS_TIC
J 0
(-3635 8410);
DISPLAY 0.574468 (-3635 8410);
WIRE 16 -1 (-3875 8575)(-2775 8575);
FORCEPROP 2 LAST SIG_NAME P12V_OCP_SFF_ISENSE_MPS_MAM
J 0
(-3635 8585);
DISPLAY 0.574468 (-3635 8585);
WIRE 16 2175 (-4375 8325)(-3650 8325);
WIRE 16 2175 (-4375 8625)(-4375 8325);
WIRE 16 2175 (-3650 8625)(-3650 8325);
WIRE 16 2175 (-4375 8625)(-3650 8625);
WIRE 16 -1 (-4450 12375)(-4450 12475);
WIRE 16 -1 (-4450 12475)(-4025 12475);
WIRE 16 -1 (-2800 12475)(-4025 12475);
FORCEPROP 2 LAST SIG_NAME P3V3_OCP_MODE_1
J 0
(-3335 12485);
DISPLAY 0.574468 (-3335 12485);
FORCEPROP 2 LASTPROP $XRERR UNIQUE?
J 0
(-3575 12485);
DISPLAY 0.638298 (-3575 12485);
PAINT MONO (-3575 12485);
DISPLAY INVISIBLE (-3575 12485);
WIRE 16 -1 (-4025 12375)(-4025 12475);
WIRE 16 -1 (-7925 9975)(-8825 9975);
FORCEPROP 2 LAST SIG_NAME P12V_OCP_SFF_BUF_EN_R
J 0
(-8760 9985);
DISPLAY 0.680851 (-8760 9985);
WIRE 16 -1 (-4100 13325)(-5300 13325);
FORCEPROP 2 LAST SIG_NAME P12V_OCP_SFF_BUF_EN_R
J 0
(-5135 13335);
DISPLAY 0.680851 (-5135 13335);
WIRE 16 -1 (-7825 9600)(-8500 9600);
FORCEPROP 2 LAST SIG_NAME P12V_OCP_SFF_EN_R
J 0
(-8410 9610);
DISPLAY 0.489362 (-8410 9610);
WIRE 16 3135 (-5375 11025)(-4125 11025);
WIRE 16 3135 (-5375 10375)(-5375 11025);
WIRE 16 3135 (-4125 10375)(-4125 11025);
WIRE 16 3135 (-5375 10375)(-4125 10375);
WIRE 16 3135 (-5350 10575)(-4150 10575);
WIRE 16 3135 (-4575 11000)(-4575 10400);
WIRE 16 3135 (-5000 11000)(-5000 10400);
WIRE 16 -1 (-4125 12900)(-5275 12900);
FORCEPROP 2 LAST SIG_NAME HP_LVC3_OCP_V3_1_P12V_PWRGD
J 0
(-5185 12910);
DISPLAY 0.680851 (-5185 12910);
WIRE 16 -1 (-3950 12575)(-4725 12575);
FORCEPROP 2 LAST SIG_NAME P3V3_OCP_SFF_EN_R
J 0
(-4710 12585);
DISPLAY 0.638298 (-4710 12585);
WIRE 16 3135 (-5350 10475)(-4150 10475);
WIRE 16 3135 (-5350 10675)(-4150 10675);
WIRE 16 3135 (-5350 10775)(-4150 10775);
WIRE 16 3135 (-5350 10875)(-4150 10875);
WIRE 16 -1 (-3275 9225)(-3875 9225);
FORCEPROP 2 LAST SIG_NAME P12V_OCP_AVIN_PD_1
J 0
(-3760 9235);
DISPLAY 0.574468 (-3760 9235);
WIRE 16 -1 (-3875 9400)(-3875 9225);
WIRE 16 -1 (-3875 9225)(-3875 9175);
WIRE 16 -1 (-3050 12375)(-2800 12375);
WIRE 16 -1 (-3050 12300)(-3050 12375);
FORCEPROP 2 LAST SIG_NAME P3V3_OCP_DVDT_1
J 0
(-3335 12385);
DISPLAY 0.574468 (-3335 12385);
FORCEPROP 2 LASTPROP $XRERR UNIQUE?
J 0
(-3575 12385);
DISPLAY 0.638298 (-3575 12385);
PAINT MONO (-3575 12385);
DISPLAY INVISIBLE (-3575 12385);
WIRE 16 -1 (-1550 12225)(-1550 12475);
WIRE 16 -1 (-2000 12475)(-1550 12475);
FORCEPROP 2 LAST SIG_NAME P3V3_OCP_GATE_1
J 0
(-1910 12485);
DISPLAY 0.574468 (-1910 12485);
FORCEPROP 2 LASTPROP $XRERR UNIQUE?
J 0
(-2150 12485);
DISPLAY 0.638298 (-2150 12485);
PAINT MONO (-2150 12485);
DISPLAY INVISIBLE (-2150 12485);
WIRE 16 -1 (-3600 12425)(-2800 12425);
FORCEPROP 2 LAST SIG_NAME P3V3_OCP_ILIMIT_1
J 0
(-3385 12435);
DISPLAY 0.574468 (-3385 12435);
FORCEPROP 2 LASTPROP $XRERR UNIQUE?
J 0
(-3625 12435);
DISPLAY 0.638298 (-3625 12435);
PAINT MONO (-3625 12435);
DISPLAY INVISIBLE (-3625 12435);
WIRE 16 -1 (-3600 12325)(-3600 12425);
WIRE 16 -1 (-3900 13325)(-3550 13325);
WIRE 16 -1 (-3550 13325)(-3550 12900);
WIRE 16 -1 (-3550 12900)(-3550 12575);
WIRE 16 -1 (-3925 12900)(-3550 12900);
WIRE 16 -1 (-2800 12575)(-3550 12575);
FORCEPROP 2 LAST SIG_NAME P3V3_OCP_EN_1_R2
J 0
(-3385 12585);
DISPLAY 0.574468 (-3385 12585);
FORCEPROP 2 LASTPROP $XRERR UNIQUE?
J 0
(-3625 12585);
DISPLAY 0.638298 (-3625 12585);
PAINT MONO (-3625 12585);
DISPLAY INVISIBLE (-3625 12585);
WIRE 16 -1 (-3550 12575)(-3750 12575);
DOT 1 (-4400 9250);
DOT 1 (-3875 9225);
DOT 1 (-3525 10100);
DOT 1 (-4800 9800);
DOT 1 (-3325 13050);
DOT 1 (-7275 10200);
DOT 1 (-1550 11950);
DOT 1 (-5775 9000);
DOT 1 (-5325 9000);
DOT 1 (-5325 8445);
DOT 1 (-950 12675);
DOT 1 (-4025 12475);
DOT 1 (-3550 12575);
DOT 1 (-5693 9800);
DOT 1 (-5400 9800);
DOT 1 (-3875 9700);
DOT 1 (-4425 8575);
DOT 1 (-4200 8825);
DOT 1 (-3550 12900);
DOT 1 (-4450 12050);
DOT 1 (-5925 9950);
DOT 1 (-6880 9950);
DOT 1 (-6880 9900);
DOT 1 (-6880 9850);
DOT 1 (-6880 9800);
DOT 1 (-5693 9750);
DOT 1 (-5693 9700);
DOT 1 (-5693 9650);
DOT 1 (-5693 9600);
DOT 1 (-7425 9600);
DOT 1 (-5693 9550);
DOT 1 (-5693 9500);
DOT 1 (-7125 9400);
DOT 1 (-5400 9350);
DOT 1 (-4800 9250);
FORCENOTE
DESIGN SPECIFICATION
(-9291 13794) 0;
DISPLAY LEFT (-9291 13794);
DISPLAY 1.170213 (-9291 13794);
FORCENOTE
OCP=IMAX*1.3=1.43A
(-9275 13525) 0;
DISPLAY LEFT (-9275 13525);
DISPLAY 0.936170 (-9275 13525);
FORCENOTE
DE-POP
(-4525 10600) 0;
DISPLAY LEFT (-4525 10600);
DISPLAY 1.021277 (-4525 10600);
FORCENOTE
POP
(-4950 10400) 0;
DISPLAY LEFT (-4950 10400);
DISPLAY 1.021277 (-4950 10400);
FORCENOTE
=1.6A
(-3900 11700) 0;
DISPLAY LEFT (-3900 11700);
DISPLAY 1.021277 (-3900 11700);
PAINT WHITE (-3900 11700);
FORCENOTE
CURRENT LIMIT
(-3900 11766) 0;
DISPLAY LEFT (-3900 11766);
DISPLAY 1.021277 (-3900 11766);
PAINT WHITE (-3900 11766);
FORCENOTE
P3V3_OCP_V3
(-9275 13675) 0;
DISPLAY LEFT (-9275 13675);
DISPLAY 0.936170 (-9275 13675);
FORCENOTE
P12V_OCP_V3
(-9275 13275) 0;
DISPLAY LEFT (-9275 13275);
DISPLAY 1.021277 (-9275 13275);
FORCENOTE
IMAX=6.6A
(-9275 13200) 0;
DISPLAY LEFT (-9275 13200);
DISPLAY 1.021277 (-9275 13200);
FORCENOTE
IMAX=1.1A
(-9275 13600) 0;
DISPLAY LEFT (-9275 13600);
DISPLAY 0.936170 (-9275 13600);
FORCENOTE
ENABLE:
(-9100 9366) 0;
DISPLAY LEFT (-9100 9366);
DISPLAY 1.021277 (-9100 9366);
PAINT WHITE (-9100 9366);
FORCENOTE
TFAULT: 1.27MS
(-8550 8625) 0;
DISPLAY LEFT (-8550 8625);
DISPLAY 1.021277 (-8550 8625);
PAINT WHITE (-8550 8625);
FORCENOTE
TDELAY: 6.29MS
(-8550 8550) 0;
DISPLAY LEFT (-8550 8550);
DISPLAY 1.021277 (-8550 8550);
PAINT WHITE (-8550 8550);
FORCENOTE
VIMON(MAX)= 1.582V @ IOUT=9.09A
(-7125 8225) 0;
DISPLAY LEFT (-7125 8225);
DISPLAY 1.021277 (-7125 8225);
PAINT WHITE (-7125 8225);
FORCENOTE
MP5025A/
(-4525 10950) 0;
DISPLAY LEFT (-4525 10950);
DISPLAY 1.021277 (-4525 10950);
FORCENOTE
MP5022A
(-4525 10900) 0;
DISPLAY LEFT (-4525 10900);
DISPLAY 1.021277 (-4525 10900);
FORCENOTE
OCP=IMAX*1.3=8.58A
(-9275 13125) 0;
DISPLAY LEFT (-9275 13125);
DISPLAY 1.021277 (-9275 13125);
FORCENOTE
START UP TIME:4.7MS
(-2850 11650) 0;
DISPLAY LEFT (-2850 11650);
DISPLAY 1.021277 (-2850 11650);
PAINT WHITE (-2850 11650);
FORCENOTE
POP
(-4475 10800) 0;
DISPLAY LEFT (-4475 10800);
DISPLAY 1.021277 (-4475 10800);
FORCENOTE
POP
(-4950 10500) 0;
DISPLAY LEFT (-4950 10500);
DISPLAY 1.021277 (-4950 10500);
FORCENOTE
DE-POP
(-4950 10700) 0;
DISPLAY LEFT (-4950 10700);
DISPLAY 1.021277 (-4950 10700);
FORCENOTE
MP5022C
(-4975 10900) 0;
DISPLAY LEFT (-4975 10900);
DISPLAY 1.021277 (-4975 10900);
FORCENOTE
POP
(-4475 10700) 0;
DISPLAY LEFT (-4475 10700);
DISPLAY 1.021277 (-4475 10700);
FORCENOTE
DE-POP
(-4525 10400) 0;
DISPLAY LEFT (-4525 10400);
DISPLAY 1.021277 (-4525 10400);
FORCENOTE
START UP TIME:8.62MS
(-7600 8550) 0;
DISPLAY LEFT (-7600 8550);
DISPLAY 1.021277 (-7600 8550);
PAINT WHITE (-7600 8550);
FORCENOTE
2ND SOURCE OF PU202
(-3050 13250) 0;
DISPLAY LEFT (-3050 13250);
DISPLAY 1.595745 (-3050 13250);
FORCENOTE
FROM CPLD
(-9050 9675) 0;
DISPLAY LEFT (-9050 9675);
DISPLAY 1.021277 (-9050 9675);
FORCENOTE
FROM PRSNT BUFFER
(-5475 13450) 0;
DISPLAY LEFT (-5475 13450);
DISPLAY 1.021277 (-5475 13450);
FORCENOTE
FROM OCP_12V_PG
(-5425 13050) 0;
DISPLAY LEFT (-5425 13050);
DISPLAY 1.021277 (-5425 13050);
FORCENOTE
PR3840
(-5300 10800) 0;
DISPLAY LEFT (-5300 10800);
DISPLAY 1.021277 (-5300 10800);
FORCENOTE
PR3838
(-5300 10700) 0;
DISPLAY LEFT (-5300 10700);
DISPLAY 1.021277 (-5300 10700);
FORCENOTE
PR3843
(-5300 10500) 0;
DISPLAY LEFT (-5300 10500);
DISPLAY 1.021277 (-5300 10500);
FORCENOTE
MP5025C/
(-4975 10950) 0;
DISPLAY LEFT (-4975 10950);
DISPLAY 1.021277 (-4975 10950);
FORCENOTE
DE-POP
(-4950 10800) 0;
DISPLAY LEFT (-4950 10800);
DISPLAY 1.021277 (-4950 10800);
FORCENOTE
PC2158
(-5300 10400) 0;
DISPLAY LEFT (-5300 10400);
DISPLAY 1.021277 (-5300 10400);
FORCENOTE
FROM CPLD
(-5125 12475) 0;
DISPLAY LEFT (-5125 12475);
DISPLAY 1.021277 (-5125 12475);
FORCENOTE
PR3841
(-5300 10600) 0;
DISPLAY LEFT (-5300 10600);
DISPLAY 1.021277 (-5300 10600);
FORCENOTE
POP
(-4950 10600) 0;
DISPLAY LEFT (-4950 10600);
DISPLAY 1.021277 (-4950 10600);
FORCENOTE
DE-POP
(-4525 10500) 0;
DISPLAY LEFT (-4525 10500);
DISPLAY 1.021277 (-4525 10500);
FORCENOTE
PU204 OPTIONAL BOM
(-5350 11050) 0;
DISPLAY LEFT (-5350 11050);
DISPLAY 1.021277 (-5350 11050);
FORCENOTE
FROM PRSNT BUFFER
(-9050 9875) 0;
DISPLAY LEFT (-9050 9875);
DISPLAY 1.021277 (-9050 9875);
FORCENOTE
VTH>1.391V(HIGH)
(-9100 9300) 0;
DISPLAY LEFT (-9100 9300);
DISPLAY 1.021277 (-9100 9300);
PAINT WHITE (-9100 9300);
FORCENOTE
2ND SOURCE OF PU203
(-7225 10575) 0;
DISPLAY LEFT (-7225 10575);
DISPLAY 1.595745 (-7225 10575);
QUIT
